FILE_TYPE = MACRO_DRAWING;
SET COLOR_WIRE YELLOW;
SET COLOR_PROP ORANGE;
SET COLOR_DOT WHITE;
SET COLOR_ARC YELLOW;
SET COLOR_BODY GREEN;
SET COLOR_NOTE PURPLE;
SET PROP_DISPLAY VALUE;
SET PAGE_NUMBER P91;
FORCEADD OFFPAGE..5
(-7925 1950);
FORCEPROP 2 LAST $XR0 16 
J 0
(-8149 1950);
DISPLAY 0.638298 (-8149 1950);
PAINT MONO (-8149 1950);
FORCEPROP 2 LAST PATH I1
J 0
(-8125 2000);
DISPLAY 1.021277 (-8125 2000);
DISPLAY INVISIBLE (-8125 2000);
FORCEPROP 1 LAST COMMENT_BODY TRUE
J 0
(-7825 1875);
DISPLAY 0.872340 (-7825 1875);
PAINT GREEN (-7825 1875);
DISPLAY INVISIBLE (-7825 1875);
FORCEPROP 1 LAST OFFPAGE TRUE
J 0
(-7600 1825);
DISPLAY 0.872340 (-7600 1825);
PAINT GREEN (-7600 1825);
DISPLAY INVISIBLE (-7600 1825);
FORCEPROP 2 LAST CDS_LIB mstr_standard
J 0
(-7925 1950);
DISPLAY 0.808511 (-7925 1950);
DISPLAY INVISIBLE (-7925 1950);
FORCEADD OFFPAGE..6
(-7925 3600);
FORCEPROP 2 LAST $XR0 16 
J 0
(-8204 3600);
DISPLAY 0.638298 (-8204 3600);
PAINT MONO (-8204 3600);
FORCEPROP 2 LAST PATH I10
J 0
(-8200 3650);
DISPLAY 1.021277 (-8200 3650);
DISPLAY INVISIBLE (-8200 3650);
FORCEPROP 1 LAST COMMENT_BODY TRUE
J 0
(-7825 3525);
DISPLAY 0.872340 (-7825 3525);
PAINT GREEN (-7825 3525);
DISPLAY INVISIBLE (-7825 3525);
FORCEPROP 1 LAST OFFPAGE TRUE
J 0
(-7600 3475);
DISPLAY 0.872340 (-7600 3475);
PAINT GREEN (-7600 3475);
DISPLAY INVISIBLE (-7600 3475);
FORCEPROP 2 LAST CDS_LIB mstr_standard
J 0
(-7925 3600);
DISPLAY 0.723404 (-7925 3600);
PAINT MONO (-7925 3600);
DISPLAY INVISIBLE (-7925 3600);
FORCEADD TAP..1
(-5625 4100);
FORCEPROP 3 LASTPIN (-5675 4100) SIG_NAME M_G_CPU0_SA_DQ<5>
J 0
(-5665 4110);
DISPLAY 0.659574 (-5665 4110);
PAINT MONO (-5665 4110);
DISPLAY INVISIBLE (-5665 4110);
FORCEPROP 1 LASTPIN (-5675 4100) BN 5
J 0
(-5687 4108);
DISPLAY 0.489362 (-5687 4108);
PAINT GREEN (-5687 4108);
FORCEPROP 2 LAST CDS_LIB mstr_standard
J 0
(-5625 4100);
DISPLAY 0.723404 (-5625 4100);
PAINT MONO (-5625 4100);
DISPLAY INVISIBLE (-5625 4100);
FORCEPROP 1 LAST BODY_TYPE PLUMBING
J 0
(-5625 4150);
DISPLAY 0.872340 (-5625 4150);
PAINT GREEN (-5625 4150);
DISPLAY INVISIBLE (-5625 4150);
FORCEPROP 1 LAST HDL_TAP TRUE
J 0
(-5300 3975);
DISPLAY 0.872340 (-5300 3975);
DISPLAY INVISIBLE (-5300 3975);
FORCEPROP 1 LAST PATH I100
J 0
(-5627 4100);
DISPLAY 0.872340 (-5627 4100);
PAINT GREEN (-5627 4100);
DISPLAY INVISIBLE (-5627 4100);
FORCEADD TAP..1
(-5625 4250);
FORCEPROP 3 LASTPIN (-5675 4250) SIG_NAME M_G_CPU0_SA_DQ<8>
J 0
(-5665 4260);
DISPLAY 0.659574 (-5665 4260);
PAINT MONO (-5665 4260);
DISPLAY INVISIBLE (-5665 4260);
FORCEPROP 1 LASTPIN (-5675 4250) BN 8
J 0
(-5687 4258);
DISPLAY 0.489362 (-5687 4258);
PAINT GREEN (-5687 4258);
FORCEPROP 2 LAST CDS_LIB mstr_standard
J 0
(-5625 4250);
DISPLAY 0.723404 (-5625 4250);
PAINT MONO (-5625 4250);
DISPLAY INVISIBLE (-5625 4250);
FORCEPROP 1 LAST BODY_TYPE PLUMBING
J 0
(-5625 4300);
DISPLAY 0.872340 (-5625 4300);
PAINT GREEN (-5625 4300);
DISPLAY INVISIBLE (-5625 4300);
FORCEPROP 1 LAST HDL_TAP TRUE
J 0
(-5300 4125);
DISPLAY 0.872340 (-5300 4125);
DISPLAY INVISIBLE (-5300 4125);
FORCEPROP 1 LAST PATH I101
J 0
(-5627 4250);
DISPLAY 0.872340 (-5627 4250);
PAINT GREEN (-5627 4250);
DISPLAY INVISIBLE (-5627 4250);
FORCEADD TAP..1
(-5625 4300);
FORCEPROP 3 LASTPIN (-5675 4300) SIG_NAME M_G_CPU0_SA_DQ<9>
J 0
(-5665 4310);
DISPLAY 0.659574 (-5665 4310);
PAINT MONO (-5665 4310);
DISPLAY INVISIBLE (-5665 4310);
FORCEPROP 1 LASTPIN (-5675 4300) BN 9
J 0
(-5687 4308);
DISPLAY 0.489362 (-5687 4308);
PAINT GREEN (-5687 4308);
FORCEPROP 2 LAST CDS_LIB mstr_standard
J 0
(-5625 4300);
DISPLAY 0.723404 (-5625 4300);
PAINT MONO (-5625 4300);
DISPLAY INVISIBLE (-5625 4300);
FORCEPROP 1 LAST BODY_TYPE PLUMBING
J 0
(-5625 4350);
DISPLAY 0.872340 (-5625 4350);
PAINT GREEN (-5625 4350);
DISPLAY INVISIBLE (-5625 4350);
FORCEPROP 1 LAST HDL_TAP TRUE
J 0
(-5300 4175);
DISPLAY 0.872340 (-5300 4175);
DISPLAY INVISIBLE (-5300 4175);
FORCEPROP 1 LAST PATH I102
J 0
(-5627 4300);
DISPLAY 0.872340 (-5627 4300);
PAINT GREEN (-5627 4300);
DISPLAY INVISIBLE (-5627 4300);
FORCEADD TAP..1
(-5625 4200);
FORCEPROP 3 LASTPIN (-5675 4200) SIG_NAME M_G_CPU0_SA_DQ<7>
J 0
(-5665 4210);
DISPLAY 0.659574 (-5665 4210);
PAINT MONO (-5665 4210);
DISPLAY INVISIBLE (-5665 4210);
FORCEPROP 1 LASTPIN (-5675 4200) BN 7
J 0
(-5687 4208);
DISPLAY 0.489362 (-5687 4208);
PAINT GREEN (-5687 4208);
FORCEPROP 2 LAST CDS_LIB mstr_standard
J 0
(-5625 4200);
DISPLAY 0.723404 (-5625 4200);
PAINT MONO (-5625 4200);
DISPLAY INVISIBLE (-5625 4200);
FORCEPROP 1 LAST BODY_TYPE PLUMBING
J 0
(-5625 4250);
DISPLAY 0.872340 (-5625 4250);
PAINT GREEN (-5625 4250);
DISPLAY INVISIBLE (-5625 4250);
FORCEPROP 1 LAST HDL_TAP TRUE
J 0
(-5300 4075);
DISPLAY 0.872340 (-5300 4075);
DISPLAY INVISIBLE (-5300 4075);
FORCEPROP 1 LAST PATH I103
J 0
(-5627 4200);
DISPLAY 0.872340 (-5627 4200);
PAINT GREEN (-5627 4200);
DISPLAY INVISIBLE (-5627 4200);
FORCEADD TAP..1
(-5625 4450);
FORCEPROP 3 LASTPIN (-5675 4450) SIG_NAME M_G_CPU0_SA_DQ<12>
J 0
(-5665 4460);
DISPLAY 0.659574 (-5665 4460);
PAINT MONO (-5665 4460);
DISPLAY INVISIBLE (-5665 4460);
FORCEPROP 1 LASTPIN (-5675 4450) BN 12
J 0
(-5687 4458);
DISPLAY 0.489362 (-5687 4458);
PAINT GREEN (-5687 4458);
FORCEPROP 2 LAST CDS_LIB mstr_standard
J 0
(-5625 4450);
DISPLAY 0.723404 (-5625 4450);
PAINT MONO (-5625 4450);
DISPLAY INVISIBLE (-5625 4450);
FORCEPROP 1 LAST BODY_TYPE PLUMBING
J 0
(-5625 4500);
DISPLAY 0.872340 (-5625 4500);
PAINT GREEN (-5625 4500);
DISPLAY INVISIBLE (-5625 4500);
FORCEPROP 1 LAST HDL_TAP TRUE
J 0
(-5300 4325);
DISPLAY 0.872340 (-5300 4325);
DISPLAY INVISIBLE (-5300 4325);
FORCEPROP 1 LAST PATH I104
J 0
(-5627 4450);
DISPLAY 0.872340 (-5627 4450);
PAINT GREEN (-5627 4450);
DISPLAY INVISIBLE (-5627 4450);
FORCEADD TAP..1
(-5625 4400);
FORCEPROP 3 LASTPIN (-5675 4400) SIG_NAME M_G_CPU0_SA_DQ<11>
J 0
(-5665 4410);
DISPLAY 0.659574 (-5665 4410);
PAINT MONO (-5665 4410);
DISPLAY INVISIBLE (-5665 4410);
FORCEPROP 1 LASTPIN (-5675 4400) BN 11
J 0
(-5687 4408);
DISPLAY 0.489362 (-5687 4408);
PAINT GREEN (-5687 4408);
FORCEPROP 2 LAST CDS_LIB mstr_standard
J 0
(-5625 4400);
DISPLAY 0.723404 (-5625 4400);
PAINT MONO (-5625 4400);
DISPLAY INVISIBLE (-5625 4400);
FORCEPROP 1 LAST BODY_TYPE PLUMBING
J 0
(-5625 4450);
DISPLAY 0.872340 (-5625 4450);
PAINT GREEN (-5625 4450);
DISPLAY INVISIBLE (-5625 4450);
FORCEPROP 1 LAST HDL_TAP TRUE
J 0
(-5300 4275);
DISPLAY 0.872340 (-5300 4275);
DISPLAY INVISIBLE (-5300 4275);
FORCEPROP 1 LAST PATH I105
J 0
(-5627 4400);
DISPLAY 0.872340 (-5627 4400);
PAINT GREEN (-5627 4400);
DISPLAY INVISIBLE (-5627 4400);
FORCEADD TAP..1
(-5625 4350);
FORCEPROP 3 LASTPIN (-5675 4350) SIG_NAME M_G_CPU0_SA_DQ<10>
J 0
(-5665 4360);
DISPLAY 0.659574 (-5665 4360);
PAINT MONO (-5665 4360);
DISPLAY INVISIBLE (-5665 4360);
FORCEPROP 1 LASTPIN (-5675 4350) BN 10
J 0
(-5687 4358);
DISPLAY 0.489362 (-5687 4358);
PAINT GREEN (-5687 4358);
FORCEPROP 2 LAST CDS_LIB mstr_standard
J 0
(-5625 4350);
DISPLAY 0.723404 (-5625 4350);
PAINT MONO (-5625 4350);
DISPLAY INVISIBLE (-5625 4350);
FORCEPROP 1 LAST BODY_TYPE PLUMBING
J 0
(-5625 4400);
DISPLAY 0.872340 (-5625 4400);
PAINT GREEN (-5625 4400);
DISPLAY INVISIBLE (-5625 4400);
FORCEPROP 1 LAST HDL_TAP TRUE
J 0
(-5300 4225);
DISPLAY 0.872340 (-5300 4225);
DISPLAY INVISIBLE (-5300 4225);
FORCEPROP 1 LAST PATH I106
J 0
(-5627 4350);
DISPLAY 0.872340 (-5627 4350);
PAINT GREEN (-5627 4350);
DISPLAY INVISIBLE (-5627 4350);
FORCEADD TAP..1
(-5625 4500);
FORCEPROP 3 LASTPIN (-5675 4500) SIG_NAME M_G_CPU0_SA_DQ<13>
J 0
(-5665 4510);
DISPLAY 0.659574 (-5665 4510);
PAINT MONO (-5665 4510);
DISPLAY INVISIBLE (-5665 4510);
FORCEPROP 1 LASTPIN (-5675 4500) BN 13
J 0
(-5687 4508);
DISPLAY 0.489362 (-5687 4508);
PAINT GREEN (-5687 4508);
FORCEPROP 2 LAST CDS_LIB mstr_standard
J 0
(-5625 4500);
DISPLAY 0.723404 (-5625 4500);
PAINT MONO (-5625 4500);
DISPLAY INVISIBLE (-5625 4500);
FORCEPROP 1 LAST BODY_TYPE PLUMBING
J 0
(-5625 4550);
DISPLAY 0.872340 (-5625 4550);
PAINT GREEN (-5625 4550);
DISPLAY INVISIBLE (-5625 4550);
FORCEPROP 1 LAST HDL_TAP TRUE
J 0
(-5300 4375);
DISPLAY 0.872340 (-5300 4375);
DISPLAY INVISIBLE (-5300 4375);
FORCEPROP 1 LAST PATH I107
J 0
(-5627 4500);
DISPLAY 0.872340 (-5627 4500);
PAINT GREEN (-5627 4500);
DISPLAY INVISIBLE (-5627 4500);
FORCEADD TAP..1
(-5625 4550);
FORCEPROP 3 LASTPIN (-5675 4550) SIG_NAME M_G_CPU0_SA_DQ<14>
J 0
(-5665 4560);
DISPLAY 0.659574 (-5665 4560);
PAINT MONO (-5665 4560);
DISPLAY INVISIBLE (-5665 4560);
FORCEPROP 1 LASTPIN (-5675 4550) BN 14
J 0
(-5687 4558);
DISPLAY 0.489362 (-5687 4558);
PAINT GREEN (-5687 4558);
FORCEPROP 2 LAST CDS_LIB mstr_standard
J 0
(-5625 4550);
DISPLAY 0.723404 (-5625 4550);
PAINT MONO (-5625 4550);
DISPLAY INVISIBLE (-5625 4550);
FORCEPROP 1 LAST BODY_TYPE PLUMBING
J 0
(-5625 4600);
DISPLAY 0.872340 (-5625 4600);
PAINT GREEN (-5625 4600);
DISPLAY INVISIBLE (-5625 4600);
FORCEPROP 1 LAST HDL_TAP TRUE
J 0
(-5300 4425);
DISPLAY 0.872340 (-5300 4425);
DISPLAY INVISIBLE (-5300 4425);
FORCEPROP 1 LAST PATH I108
J 0
(-5627 4550);
DISPLAY 0.872340 (-5627 4550);
PAINT GREEN (-5627 4550);
DISPLAY INVISIBLE (-5627 4550);
FORCEADD TAP..1
(-5625 4700);
FORCEPROP 3 LASTPIN (-5675 4700) SIG_NAME M_G_CPU0_SA_DQ<17>
J 0
(-5665 4710);
DISPLAY 0.659574 (-5665 4710);
PAINT MONO (-5665 4710);
DISPLAY INVISIBLE (-5665 4710);
FORCEPROP 1 LASTPIN (-5675 4700) BN 17
J 0
(-5687 4708);
DISPLAY 0.489362 (-5687 4708);
PAINT GREEN (-5687 4708);
FORCEPROP 2 LAST CDS_LIB mstr_standard
J 0
(-5625 4700);
DISPLAY 0.723404 (-5625 4700);
PAINT MONO (-5625 4700);
DISPLAY INVISIBLE (-5625 4700);
FORCEPROP 1 LAST BODY_TYPE PLUMBING
J 0
(-5625 4750);
DISPLAY 0.872340 (-5625 4750);
PAINT GREEN (-5625 4750);
DISPLAY INVISIBLE (-5625 4750);
FORCEPROP 1 LAST HDL_TAP TRUE
J 0
(-5300 4575);
DISPLAY 0.872340 (-5300 4575);
DISPLAY INVISIBLE (-5300 4575);
FORCEPROP 1 LAST PATH I109
J 0
(-5627 4700);
DISPLAY 0.872340 (-5627 4700);
PAINT GREEN (-5627 4700);
DISPLAY INVISIBLE (-5627 4700);
FORCEADD OFFPAGE..6
(-7925 4050);
FORCEPROP 2 LAST $XR0 16 
J 0
(-8204 4050);
DISPLAY 0.638298 (-8204 4050);
PAINT MONO (-8204 4050);
FORCEPROP 2 LAST PATH I11
J 0
(-8200 4100);
DISPLAY 1.021277 (-8200 4100);
DISPLAY INVISIBLE (-8200 4100);
FORCEPROP 1 LAST COMMENT_BODY TRUE
J 0
(-7825 3975);
DISPLAY 0.872340 (-7825 3975);
PAINT GREEN (-7825 3975);
DISPLAY INVISIBLE (-7825 3975);
FORCEPROP 1 LAST OFFPAGE TRUE
J 0
(-7600 3925);
DISPLAY 0.872340 (-7600 3925);
PAINT GREEN (-7600 3925);
DISPLAY INVISIBLE (-7600 3925);
FORCEPROP 2 LAST CDS_LIB mstr_standard
J 0
(-7925 4050);
DISPLAY 0.723404 (-7925 4050);
PAINT MONO (-7925 4050);
DISPLAY INVISIBLE (-7925 4050);
FORCEADD TAP..1
(-5625 4650);
FORCEPROP 3 LASTPIN (-5675 4650) SIG_NAME M_G_CPU0_SA_DQ<16>
J 0
(-5665 4660);
DISPLAY 0.659574 (-5665 4660);
PAINT MONO (-5665 4660);
DISPLAY INVISIBLE (-5665 4660);
FORCEPROP 1 LASTPIN (-5675 4650) BN 16
J 0
(-5687 4658);
DISPLAY 0.489362 (-5687 4658);
PAINT GREEN (-5687 4658);
FORCEPROP 2 LAST CDS_LIB mstr_standard
J 0
(-5625 4650);
DISPLAY 0.723404 (-5625 4650);
PAINT MONO (-5625 4650);
DISPLAY INVISIBLE (-5625 4650);
FORCEPROP 1 LAST BODY_TYPE PLUMBING
J 0
(-5625 4700);
DISPLAY 0.872340 (-5625 4700);
PAINT GREEN (-5625 4700);
DISPLAY INVISIBLE (-5625 4700);
FORCEPROP 1 LAST HDL_TAP TRUE
J 0
(-5300 4525);
DISPLAY 0.872340 (-5300 4525);
DISPLAY INVISIBLE (-5300 4525);
FORCEPROP 1 LAST PATH I110
J 0
(-5627 4650);
DISPLAY 0.872340 (-5627 4650);
PAINT GREEN (-5627 4650);
DISPLAY INVISIBLE (-5627 4650);
FORCEADD TAP..1
(-5625 4600);
FORCEPROP 3 LASTPIN (-5675 4600) SIG_NAME M_G_CPU0_SA_DQ<15>
J 0
(-5665 4610);
DISPLAY 0.659574 (-5665 4610);
PAINT MONO (-5665 4610);
DISPLAY INVISIBLE (-5665 4610);
FORCEPROP 1 LASTPIN (-5675 4600) BN 15
J 0
(-5687 4608);
DISPLAY 0.489362 (-5687 4608);
PAINT GREEN (-5687 4608);
FORCEPROP 2 LAST CDS_LIB mstr_standard
J 0
(-5625 4600);
DISPLAY 0.723404 (-5625 4600);
PAINT MONO (-5625 4600);
DISPLAY INVISIBLE (-5625 4600);
FORCEPROP 1 LAST BODY_TYPE PLUMBING
J 0
(-5625 4650);
DISPLAY 0.872340 (-5625 4650);
PAINT GREEN (-5625 4650);
DISPLAY INVISIBLE (-5625 4650);
FORCEPROP 1 LAST HDL_TAP TRUE
J 0
(-5300 4475);
DISPLAY 0.872340 (-5300 4475);
DISPLAY INVISIBLE (-5300 4475);
FORCEPROP 1 LAST PATH I111
J 0
(-5627 4600);
DISPLAY 0.872340 (-5627 4600);
PAINT GREEN (-5627 4600);
DISPLAY INVISIBLE (-5627 4600);
FORCEADD TAP..1
(-5625 4750);
FORCEPROP 3 LASTPIN (-5675 4750) SIG_NAME M_G_CPU0_SA_DQ<18>
J 0
(-5665 4760);
DISPLAY 0.659574 (-5665 4760);
PAINT MONO (-5665 4760);
DISPLAY INVISIBLE (-5665 4760);
FORCEPROP 1 LASTPIN (-5675 4750) BN 18
J 0
(-5687 4758);
DISPLAY 0.489362 (-5687 4758);
PAINT GREEN (-5687 4758);
FORCEPROP 2 LAST CDS_LIB mstr_standard
J 0
(-5625 4750);
DISPLAY 0.723404 (-5625 4750);
PAINT MONO (-5625 4750);
DISPLAY INVISIBLE (-5625 4750);
FORCEPROP 1 LAST BODY_TYPE PLUMBING
J 0
(-5625 4800);
DISPLAY 0.872340 (-5625 4800);
PAINT GREEN (-5625 4800);
DISPLAY INVISIBLE (-5625 4800);
FORCEPROP 1 LAST HDL_TAP TRUE
J 0
(-5300 4625);
DISPLAY 0.872340 (-5300 4625);
DISPLAY INVISIBLE (-5300 4625);
FORCEPROP 1 LAST PATH I112
J 0
(-5627 4750);
DISPLAY 0.872340 (-5627 4750);
PAINT GREEN (-5627 4750);
DISPLAY INVISIBLE (-5627 4750);
FORCEADD TAP..1
(-5625 4800);
FORCEPROP 3 LASTPIN (-5675 4800) SIG_NAME M_G_CPU0_SA_DQ<19>
J 0
(-5665 4810);
DISPLAY 0.659574 (-5665 4810);
PAINT MONO (-5665 4810);
DISPLAY INVISIBLE (-5665 4810);
FORCEPROP 1 LASTPIN (-5675 4800) BN 19
J 0
(-5687 4808);
DISPLAY 0.489362 (-5687 4808);
PAINT GREEN (-5687 4808);
FORCEPROP 2 LAST CDS_LIB mstr_standard
J 0
(-5625 4800);
DISPLAY 0.723404 (-5625 4800);
PAINT MONO (-5625 4800);
DISPLAY INVISIBLE (-5625 4800);
FORCEPROP 1 LAST BODY_TYPE PLUMBING
J 0
(-5625 4850);
DISPLAY 0.872340 (-5625 4850);
PAINT GREEN (-5625 4850);
DISPLAY INVISIBLE (-5625 4850);
FORCEPROP 1 LAST HDL_TAP TRUE
J 0
(-5300 4675);
DISPLAY 0.872340 (-5300 4675);
DISPLAY INVISIBLE (-5300 4675);
FORCEPROP 1 LAST PATH I113
J 0
(-5627 4800);
DISPLAY 0.872340 (-5627 4800);
PAINT GREEN (-5627 4800);
DISPLAY INVISIBLE (-5627 4800);
FORCEADD TAP..1
(-5625 4950);
FORCEPROP 3 LASTPIN (-5675 4950) SIG_NAME M_G_CPU0_SA_DQ<22>
J 0
(-5665 4960);
DISPLAY 0.659574 (-5665 4960);
PAINT MONO (-5665 4960);
DISPLAY INVISIBLE (-5665 4960);
FORCEPROP 1 LASTPIN (-5675 4950) BN 22
J 0
(-5687 4958);
DISPLAY 0.489362 (-5687 4958);
PAINT GREEN (-5687 4958);
FORCEPROP 2 LAST CDS_LIB mstr_standard
J 0
(-5625 4950);
DISPLAY 0.723404 (-5625 4950);
PAINT MONO (-5625 4950);
DISPLAY INVISIBLE (-5625 4950);
FORCEPROP 1 LAST BODY_TYPE PLUMBING
J 0
(-5625 5000);
DISPLAY 0.872340 (-5625 5000);
PAINT GREEN (-5625 5000);
DISPLAY INVISIBLE (-5625 5000);
FORCEPROP 1 LAST HDL_TAP TRUE
J 0
(-5300 4825);
DISPLAY 0.872340 (-5300 4825);
DISPLAY INVISIBLE (-5300 4825);
FORCEPROP 1 LAST PATH I114
J 0
(-5627 4950);
DISPLAY 0.872340 (-5627 4950);
PAINT GREEN (-5627 4950);
DISPLAY INVISIBLE (-5627 4950);
FORCEADD TAP..1
(-5625 4900);
FORCEPROP 3 LASTPIN (-5675 4900) SIG_NAME M_G_CPU0_SA_DQ<21>
J 0
(-5665 4910);
DISPLAY 0.659574 (-5665 4910);
PAINT MONO (-5665 4910);
DISPLAY INVISIBLE (-5665 4910);
FORCEPROP 1 LASTPIN (-5675 4900) BN 21
J 0
(-5687 4908);
DISPLAY 0.489362 (-5687 4908);
PAINT GREEN (-5687 4908);
FORCEPROP 2 LAST CDS_LIB mstr_standard
J 0
(-5625 4900);
DISPLAY 0.723404 (-5625 4900);
PAINT MONO (-5625 4900);
DISPLAY INVISIBLE (-5625 4900);
FORCEPROP 1 LAST BODY_TYPE PLUMBING
J 0
(-5625 4950);
DISPLAY 0.872340 (-5625 4950);
PAINT GREEN (-5625 4950);
DISPLAY INVISIBLE (-5625 4950);
FORCEPROP 1 LAST HDL_TAP TRUE
J 0
(-5300 4775);
DISPLAY 0.872340 (-5300 4775);
DISPLAY INVISIBLE (-5300 4775);
FORCEPROP 1 LAST PATH I115
J 0
(-5627 4900);
DISPLAY 0.872340 (-5627 4900);
PAINT GREEN (-5627 4900);
DISPLAY INVISIBLE (-5627 4900);
FORCEADD TAP..1
(-5625 4850);
FORCEPROP 3 LASTPIN (-5675 4850) SIG_NAME M_G_CPU0_SA_DQ<20>
J 0
(-5665 4860);
DISPLAY 0.659574 (-5665 4860);
PAINT MONO (-5665 4860);
DISPLAY INVISIBLE (-5665 4860);
FORCEPROP 1 LASTPIN (-5675 4850) BN 20
J 0
(-5687 4858);
DISPLAY 0.489362 (-5687 4858);
PAINT GREEN (-5687 4858);
FORCEPROP 2 LAST CDS_LIB mstr_standard
J 0
(-5625 4850);
DISPLAY 0.723404 (-5625 4850);
PAINT MONO (-5625 4850);
DISPLAY INVISIBLE (-5625 4850);
FORCEPROP 1 LAST BODY_TYPE PLUMBING
J 0
(-5625 4900);
DISPLAY 0.872340 (-5625 4900);
PAINT GREEN (-5625 4900);
DISPLAY INVISIBLE (-5625 4900);
FORCEPROP 1 LAST HDL_TAP TRUE
J 0
(-5300 4725);
DISPLAY 0.872340 (-5300 4725);
DISPLAY INVISIBLE (-5300 4725);
FORCEPROP 1 LAST PATH I116
J 0
(-5627 4850);
DISPLAY 0.872340 (-5627 4850);
PAINT GREEN (-5627 4850);
DISPLAY INVISIBLE (-5627 4850);
FORCEADD TAP..1
(-5625 5050);
FORCEPROP 3 LASTPIN (-5675 5050) SIG_NAME M_G_CPU0_SA_DQ<24>
J 0
(-5665 5060);
DISPLAY 0.659574 (-5665 5060);
PAINT MONO (-5665 5060);
DISPLAY INVISIBLE (-5665 5060);
FORCEPROP 1 LASTPIN (-5675 5050) BN 24
J 0
(-5687 5058);
DISPLAY 0.489362 (-5687 5058);
PAINT GREEN (-5687 5058);
FORCEPROP 2 LAST CDS_LIB mstr_standard
J 0
(-5625 5050);
DISPLAY 0.723404 (-5625 5050);
PAINT MONO (-5625 5050);
DISPLAY INVISIBLE (-5625 5050);
FORCEPROP 1 LAST BODY_TYPE PLUMBING
J 0
(-5625 5100);
DISPLAY 0.872340 (-5625 5100);
PAINT GREEN (-5625 5100);
DISPLAY INVISIBLE (-5625 5100);
FORCEPROP 1 LAST HDL_TAP TRUE
J 0
(-5300 4925);
DISPLAY 0.872340 (-5300 4925);
DISPLAY INVISIBLE (-5300 4925);
FORCEPROP 1 LAST PATH I117
J 0
(-5627 5050);
DISPLAY 0.872340 (-5627 5050);
PAINT GREEN (-5627 5050);
DISPLAY INVISIBLE (-5627 5050);
FORCEADD TAP..1
(-5625 5000);
FORCEPROP 3 LASTPIN (-5675 5000) SIG_NAME M_G_CPU0_SA_DQ<23>
J 0
(-5665 5010);
DISPLAY 0.659574 (-5665 5010);
PAINT MONO (-5665 5010);
DISPLAY INVISIBLE (-5665 5010);
FORCEPROP 1 LASTPIN (-5675 5000) BN 23
J 0
(-5687 5008);
DISPLAY 0.489362 (-5687 5008);
PAINT GREEN (-5687 5008);
FORCEPROP 2 LAST CDS_LIB mstr_standard
J 0
(-5625 5000);
DISPLAY 0.723404 (-5625 5000);
PAINT MONO (-5625 5000);
DISPLAY INVISIBLE (-5625 5000);
FORCEPROP 1 LAST BODY_TYPE PLUMBING
J 0
(-5625 5050);
DISPLAY 0.872340 (-5625 5050);
PAINT GREEN (-5625 5050);
DISPLAY INVISIBLE (-5625 5050);
FORCEPROP 1 LAST HDL_TAP TRUE
J 0
(-5300 4875);
DISPLAY 0.872340 (-5300 4875);
DISPLAY INVISIBLE (-5300 4875);
FORCEPROP 1 LAST PATH I118
J 0
(-5627 5000);
DISPLAY 0.872340 (-5627 5000);
PAINT GREEN (-5627 5000);
DISPLAY INVISIBLE (-5627 5000);
FORCEADD TAP..1
(-5625 5150);
FORCEPROP 3 LASTPIN (-5675 5150) SIG_NAME M_G_CPU0_SA_DQ<26>
J 0
(-5665 5160);
DISPLAY 0.659574 (-5665 5160);
PAINT MONO (-5665 5160);
DISPLAY INVISIBLE (-5665 5160);
FORCEPROP 1 LASTPIN (-5675 5150) BN 26
J 0
(-5687 5158);
DISPLAY 0.489362 (-5687 5158);
PAINT GREEN (-5687 5158);
FORCEPROP 2 LAST CDS_LIB mstr_standard
J 0
(-5625 5150);
DISPLAY 0.723404 (-5625 5150);
PAINT MONO (-5625 5150);
DISPLAY INVISIBLE (-5625 5150);
FORCEPROP 1 LAST BODY_TYPE PLUMBING
J 0
(-5625 5200);
DISPLAY 0.872340 (-5625 5200);
PAINT GREEN (-5625 5200);
DISPLAY INVISIBLE (-5625 5200);
FORCEPROP 1 LAST HDL_TAP TRUE
J 0
(-5300 5025);
DISPLAY 0.872340 (-5300 5025);
DISPLAY INVISIBLE (-5300 5025);
FORCEPROP 1 LAST PATH I119
J 0
(-5627 5150);
DISPLAY 0.872340 (-5627 5150);
PAINT GREEN (-5627 5150);
DISPLAY INVISIBLE (-5627 5150);
FORCEADD OFFPAGE..1
(-7925 4100);
FORCEPROP 2 LAST $XR0 16 
J 0
(-8176 4100);
DISPLAY 0.638298 (-8176 4100);
PAINT MONO (-8176 4100);
FORCEPROP 2 LAST PATH I12
J 0
(-8175 4150);
DISPLAY 1.021277 (-8175 4150);
DISPLAY INVISIBLE (-8175 4150);
FORCEPROP 1 LAST COMMENT_BODY TRUE
J 0
(-7800 4000);
DISPLAY 0.872340 (-7800 4000);
PAINT GREEN (-7800 4000);
DISPLAY INVISIBLE (-7800 4000);
FORCEPROP 1 LAST OFFPAGE TRUE
J 0
(-7600 3975);
DISPLAY 0.872340 (-7600 3975);
PAINT GREEN (-7600 3975);
DISPLAY INVISIBLE (-7600 3975);
FORCEPROP 2 LAST CDS_LIB mstr_standard
J 0
(-7925 4100);
DISPLAY 0.808511 (-7925 4100);
DISPLAY INVISIBLE (-7925 4100);
FORCEADD TAP..1
(-5625 5200);
FORCEPROP 3 LASTPIN (-5675 5200) SIG_NAME M_G_CPU0_SA_DQ<27>
J 0
(-5665 5210);
DISPLAY 0.659574 (-5665 5210);
PAINT MONO (-5665 5210);
DISPLAY INVISIBLE (-5665 5210);
FORCEPROP 1 LASTPIN (-5675 5200) BN 27
J 0
(-5687 5208);
DISPLAY 0.489362 (-5687 5208);
PAINT GREEN (-5687 5208);
FORCEPROP 2 LAST CDS_LIB mstr_standard
J 0
(-5625 5200);
DISPLAY 0.723404 (-5625 5200);
PAINT MONO (-5625 5200);
DISPLAY INVISIBLE (-5625 5200);
FORCEPROP 1 LAST BODY_TYPE PLUMBING
J 0
(-5625 5250);
DISPLAY 0.872340 (-5625 5250);
PAINT GREEN (-5625 5250);
DISPLAY INVISIBLE (-5625 5250);
FORCEPROP 1 LAST HDL_TAP TRUE
J 0
(-5300 5075);
DISPLAY 0.872340 (-5300 5075);
DISPLAY INVISIBLE (-5300 5075);
FORCEPROP 1 LAST PATH I120
J 0
(-5627 5200);
DISPLAY 0.872340 (-5627 5200);
PAINT GREEN (-5627 5200);
DISPLAY INVISIBLE (-5627 5200);
FORCEADD TAP..1
(-5625 5100);
FORCEPROP 3 LASTPIN (-5675 5100) SIG_NAME M_G_CPU0_SA_DQ<25>
J 0
(-5665 5110);
DISPLAY 0.659574 (-5665 5110);
PAINT MONO (-5665 5110);
DISPLAY INVISIBLE (-5665 5110);
FORCEPROP 1 LASTPIN (-5675 5100) BN 25
J 0
(-5687 5108);
DISPLAY 0.489362 (-5687 5108);
PAINT GREEN (-5687 5108);
FORCEPROP 2 LAST CDS_LIB mstr_standard
J 0
(-5625 5100);
DISPLAY 0.723404 (-5625 5100);
PAINT MONO (-5625 5100);
DISPLAY INVISIBLE (-5625 5100);
FORCEPROP 1 LAST BODY_TYPE PLUMBING
J 0
(-5625 5150);
DISPLAY 0.872340 (-5625 5150);
PAINT GREEN (-5625 5150);
DISPLAY INVISIBLE (-5625 5150);
FORCEPROP 1 LAST HDL_TAP TRUE
J 0
(-5300 4975);
DISPLAY 0.872340 (-5300 4975);
DISPLAY INVISIBLE (-5300 4975);
FORCEPROP 1 LAST PATH I121
J 0
(-5627 5100);
DISPLAY 0.872340 (-5627 5100);
PAINT GREEN (-5627 5100);
DISPLAY INVISIBLE (-5627 5100);
FORCEADD TAP..1
(-5625 5350);
FORCEPROP 3 LASTPIN (-5675 5350) SIG_NAME M_G_CPU0_SA_DQ<30>
J 0
(-5665 5360);
DISPLAY 0.659574 (-5665 5360);
PAINT MONO (-5665 5360);
DISPLAY INVISIBLE (-5665 5360);
FORCEPROP 1 LASTPIN (-5675 5350) BN 30
J 0
(-5687 5358);
DISPLAY 0.489362 (-5687 5358);
PAINT GREEN (-5687 5358);
FORCEPROP 2 LAST CDS_LIB mstr_standard
J 0
(-5625 5350);
DISPLAY 0.723404 (-5625 5350);
PAINT MONO (-5625 5350);
DISPLAY INVISIBLE (-5625 5350);
FORCEPROP 1 LAST BODY_TYPE PLUMBING
J 0
(-5625 5400);
DISPLAY 0.872340 (-5625 5400);
PAINT GREEN (-5625 5400);
DISPLAY INVISIBLE (-5625 5400);
FORCEPROP 1 LAST HDL_TAP TRUE
J 0
(-5300 5225);
DISPLAY 0.872340 (-5300 5225);
DISPLAY INVISIBLE (-5300 5225);
FORCEPROP 1 LAST PATH I122
J 0
(-5627 5350);
DISPLAY 0.872340 (-5627 5350);
PAINT GREEN (-5627 5350);
DISPLAY INVISIBLE (-5627 5350);
FORCEADD TAP..1
(-5625 5250);
FORCEPROP 3 LASTPIN (-5675 5250) SIG_NAME M_G_CPU0_SA_DQ<28>
J 0
(-5665 5260);
DISPLAY 0.659574 (-5665 5260);
PAINT MONO (-5665 5260);
DISPLAY INVISIBLE (-5665 5260);
FORCEPROP 1 LASTPIN (-5675 5250) BN 28
J 0
(-5687 5258);
DISPLAY 0.489362 (-5687 5258);
PAINT GREEN (-5687 5258);
FORCEPROP 2 LAST CDS_LIB mstr_standard
J 0
(-5625 5250);
DISPLAY 0.723404 (-5625 5250);
PAINT MONO (-5625 5250);
DISPLAY INVISIBLE (-5625 5250);
FORCEPROP 1 LAST BODY_TYPE PLUMBING
J 0
(-5625 5300);
DISPLAY 0.872340 (-5625 5300);
PAINT GREEN (-5625 5300);
DISPLAY INVISIBLE (-5625 5300);
FORCEPROP 1 LAST HDL_TAP TRUE
J 0
(-5300 5125);
DISPLAY 0.872340 (-5300 5125);
DISPLAY INVISIBLE (-5300 5125);
FORCEPROP 1 LAST PATH I123
J 0
(-5627 5250);
DISPLAY 0.872340 (-5627 5250);
PAINT GREEN (-5627 5250);
DISPLAY INVISIBLE (-5627 5250);
FORCEADD TAP..1
(-5625 5300);
FORCEPROP 3 LASTPIN (-5675 5300) SIG_NAME M_G_CPU0_SA_DQ<29>
J 0
(-5665 5310);
DISPLAY 0.659574 (-5665 5310);
PAINT MONO (-5665 5310);
DISPLAY INVISIBLE (-5665 5310);
FORCEPROP 1 LASTPIN (-5675 5300) BN 29
J 0
(-5687 5308);
DISPLAY 0.489362 (-5687 5308);
PAINT GREEN (-5687 5308);
FORCEPROP 2 LAST CDS_LIB mstr_standard
J 0
(-5625 5300);
DISPLAY 0.723404 (-5625 5300);
PAINT MONO (-5625 5300);
DISPLAY INVISIBLE (-5625 5300);
FORCEPROP 1 LAST BODY_TYPE PLUMBING
J 0
(-5625 5350);
DISPLAY 0.872340 (-5625 5350);
PAINT GREEN (-5625 5350);
DISPLAY INVISIBLE (-5625 5350);
FORCEPROP 1 LAST HDL_TAP TRUE
J 0
(-5300 5175);
DISPLAY 0.872340 (-5300 5175);
DISPLAY INVISIBLE (-5300 5175);
FORCEPROP 1 LAST PATH I124
J 0
(-5627 5300);
DISPLAY 0.872340 (-5627 5300);
PAINT GREEN (-5627 5300);
DISPLAY INVISIBLE (-5627 5300);
FORCEADD TAP..1
(-5625 5400);
FORCEPROP 3 LASTPIN (-5675 5400) SIG_NAME M_G_CPU0_SA_DQ<31>
J 0
(-5665 5410);
DISPLAY 0.659574 (-5665 5410);
PAINT MONO (-5665 5410);
DISPLAY INVISIBLE (-5665 5410);
FORCEPROP 1 LASTPIN (-5675 5400) BN 31
J 0
(-5687 5408);
DISPLAY 0.489362 (-5687 5408);
PAINT GREEN (-5687 5408);
FORCEPROP 2 LAST CDS_LIB mstr_standard
J 0
(-5625 5400);
DISPLAY 0.723404 (-5625 5400);
PAINT MONO (-5625 5400);
DISPLAY INVISIBLE (-5625 5400);
FORCEPROP 1 LAST BODY_TYPE PLUMBING
J 0
(-5625 5450);
DISPLAY 0.872340 (-5625 5450);
PAINT GREEN (-5625 5450);
DISPLAY INVISIBLE (-5625 5450);
FORCEPROP 1 LAST HDL_TAP TRUE
J 0
(-5300 5275);
DISPLAY 0.872340 (-5300 5275);
DISPLAY INVISIBLE (-5300 5275);
FORCEPROP 1 LAST PATH I125
J 0
(-5627 5400);
DISPLAY 0.872340 (-5627 5400);
PAINT GREEN (-5627 5400);
DISPLAY INVISIBLE (-5627 5400);
FORCEADD OFFPAGE..3
(-5025 5450);
FORCEPROP 2 LAST $XR0 16 
J 0
(-4811 5450);
DISPLAY 0.638298 (-4811 5450);
PAINT MONO (-4811 5450);
FORCEPROP 2 LAST PATH I126
J 0
(-4700 5500);
DISPLAY 1.021277 (-4700 5500);
DISPLAY INVISIBLE (-4700 5500);
FORCEPROP 1 LAST COMMENT_BODY TRUE
J 0
(-5075 5350);
DISPLAY 0.872340 (-5075 5350);
PAINT GREEN (-5075 5350);
DISPLAY INVISIBLE (-5075 5350);
FORCEPROP 1 LAST OFFPAGE TRUE
J 0
(-4700 5325);
DISPLAY 0.872340 (-4700 5325);
PAINT GREEN (-4700 5325);
DISPLAY INVISIBLE (-4700 5325);
FORCEPROP 2 LAST CDS_LIB mstr_standard
J 0
(-5025 5450);
DISPLAY 0.723404 (-5025 5450);
PAINT MONO (-5025 5450);
DISPLAY INVISIBLE (-5025 5450);
FORCEADD OFFPAGE..5
(-6800 1375);
FORCEPROP 2 LAST $XR0 91 
J 0
(-7024 1375);
DISPLAY 0.638298 (-7024 1375);
PAINT MONO (-7024 1375);
FORCEPROP 2 LAST PATH I127
J 0
(-7000 1425);
DISPLAY 1.021277 (-7000 1425);
DISPLAY INVISIBLE (-7000 1425);
FORCEPROP 1 LAST COMMENT_BODY TRUE
J 0
(-6700 1300);
DISPLAY 0.872340 (-6700 1300);
PAINT GREEN (-6700 1300);
DISPLAY INVISIBLE (-6700 1300);
FORCEPROP 1 LAST OFFPAGE TRUE
J 0
(-6475 1250);
DISPLAY 0.872340 (-6475 1250);
PAINT GREEN (-6475 1250);
DISPLAY INVISIBLE (-6475 1250);
FORCEPROP 2 LAST BOM_COST MEM
J 0
(-6875 1450);
DISPLAY 0.808511 (-6875 1450);
DISPLAY INVISIBLE (-6875 1450);
FORCEPROP 2 LAST CDS_LIB mstr_standard
J 0
(-6800 1375);
DISPLAY 0.808511 (-6800 1375);
DISPLAY INVISIBLE (-6800 1375);
FORCEADD GND..1
(-6025 975);
FORCEPROP 3 LASTPIN (-6025 1025) SIG_NAME GND\g
J 0
(-6015 1035);
DISPLAY 0.659574 (-6015 1035);
PAINT MONO (-6015 1035);
DISPLAY INVISIBLE (-6015 1035);
FORCEPROP 2 LAST BOM_COST MEM
J 0
(-6125 1050);
DISPLAY 0.808511 (-6125 1050);
DISPLAY INVISIBLE (-6125 1050);
FORCEPROP 1 LAST SIZE 1B
J 0
(-5950 925);
DISPLAY 0.851064 (-5950 925);
PAINT GREEN (-5950 925);
DISPLAY INVISIBLE (-5950 925);
FORCEPROP 2 LAST CDS_LIB mstr_symbols
J 0
(-6025 975);
DISPLAY 0.808511 (-6025 975);
DISPLAY INVISIBLE (-6025 975);
FORCEPROP 1 LAST BODY_TYPE PLUMBING
J 0
(-6070 932);
DISPLAY 0.340426 (-6070 932);
PAINT GREEN (-6070 932);
DISPLAY INVISIBLE (-6070 932);
FORCEPROP 1 LAST PATH I128
J 0
(-5950 975);
DISPLAY 0.872340 (-5950 975);
PAINT AQUA (-5950 975);
DISPLAY INVISIBLE (-5950 975);
FORCEPROP 1 LAST VOLTAGE 0.0
J 0
(-6070 932);
DISPLAY 0.723404 (-6070 932);
PAINT SKYBLUE (-6070 932);
DISPLAY INVISIBLE (-6070 932);
FORCEPROP 1 LAST HDL_POWER GND
J 0
(-6025 1125);
DISPLAY 0.851064 (-6025 1125);
PAINT GREEN (-6025 1125);
DISPLAY INVISIBLE (-6025 1125);
FORCEADD Q_RES..2
(-6025 1200);
FORCEPROP 1 LAST LOCATION R35
J 0
(-5980 1325);
DISPLAY 0.489362 (-5980 1325);
PAINT SKYBLUE (-5980 1325);
FORCEPROP 2 LAST SEC 1
J 0
(-5975 1425);
DISPLAY 0.808511 (-5975 1425);
PAINT MONO (-5975 1425);
DISPLAY INVISIBLE (-5975 1425);
FORCEPROP 1 LASTPIN (-6025 1300) $PN 1
J 0
(-6020 1262);
DISPLAY 0.489362 (-6020 1262);
PAINT WHITE (-6020 1262);
FORCEPROP 1 LASTPIN (-6025 1100) $PN 2
J 0
(-6020 1110);
DISPLAY 0.489362 (-6020 1110);
PAINT WHITE (-6020 1110);
FORCEPROP 0 LASTPIN (-6025 1300) XNET_PINS 3
R 1
J 0
(-6035 1310);
DISPLAY 0.808511 (-6035 1310);
PAINT MONO (-6035 1310);
DISPLAY INVISIBLE (-6035 1310);
FORCEPROP 0 LASTPIN (-6025 1100) XNET_PINS 2
R 1
J 2
(-6035 1090);
DISPLAY 0.808511 (-6035 1090);
PAINT MONO (-6035 1090);
DISPLAY INVISIBLE (-6035 1090);
FORCEPROP 1 LAST WATTAGE 1/16W
J 0
(-5985 1175);
DISPLAY 0.489362 (-5985 1175);
PAINT SKYBLUE (-5985 1175);
FORCEPROP 1 LAST MATERIAL CHIP
J 0
(-5985 1125);
DISPLAY 0.489362 (-5985 1125);
PAINT SKYBLUE (-5985 1125);
FORCEPROP 1 LAST TOLERANCE 1%
J 0
(-5980 1225);
DISPLAY 0.489362 (-5980 1225);
PAINT SKYBLUE (-5980 1225);
FORCEPROP 1 LAST VALUE 10K
J 0
(-5980 1275);
DISPLAY 0.489362 (-5980 1275);
PAINT SKYBLUE (-5980 1275);
FORCEPROP 1 LAST PART_NUMBER CS31002FB08
J 0
(-5985 1075);
DISPLAY 0.489362 (-5985 1075);
PAINT SKYBLUE (-5985 1075);
FORCEPROP 1 LAST PACK_TYPE 0402LF
J 0
(-5985 1025);
DISPLAY 0.489362 (-5985 1025);
PAINT SKYBLUE (-5985 1025);
FORCEPROP 2 LAST SEC_TYPE 0402LF
J 0
(-5975 1425);
DISPLAY 0.808511 (-5975 1425);
PAINT MONO (-5975 1425);
DISPLAY INVISIBLE (-5975 1425);
FORCEPROP 2 LAST BOM_COST MEM
J 0
(-5975 1375);
DISPLAY 0.808511 (-5975 1375);
DISPLAY INVISIBLE (-5975 1375);
FORCEPROP 2 LAST CDS_LIB pure_quanta
J 0
(-6025 1200);
DISPLAY INVISIBLE (-6025 1200);
FORCEPROP 1 LAST PATH I129
J 0
(-5975 1375);
DISPLAY 0.978723 (-5975 1375);
PAINT WHITE (-5975 1375);
DISPLAY INVISIBLE (-5975 1375);
FORCEPROP 2 LAST ROOM MEM_CH_A_CPU0_DIMM1
J 0
(-5975 1425);
DISPLAY 0.808511 (-5975 1425);
PAINT RED (-5975 1425);
DISPLAY INVISIBLE (-5975 1425);
FORCEADD OFFPAGE..1
(-7925 4250);
FORCEPROP 2 LAST $XR0 16 
J 0
(-8176 4250);
DISPLAY 0.638298 (-8176 4250);
PAINT MONO (-8176 4250);
FORCEPROP 2 LAST PATH I13
J 0
(-7875 4325);
DISPLAY 1.021277 (-7875 4325);
DISPLAY INVISIBLE (-7875 4325);
FORCEPROP 1 LAST COMMENT_BODY TRUE
J 0
(-7800 4150);
DISPLAY 0.872340 (-7800 4150);
PAINT GREEN (-7800 4150);
DISPLAY INVISIBLE (-7800 4150);
FORCEPROP 1 LAST OFFPAGE TRUE
J 0
(-7600 4125);
DISPLAY 0.872340 (-7600 4125);
PAINT GREEN (-7600 4125);
DISPLAY INVISIBLE (-7600 4125);
FORCEPROP 2 LAST CDS_LIB mstr_standard
J 0
(-7925 4250);
DISPLAY 0.808511 (-7925 4250);
DISPLAY INVISIBLE (-7925 4250);
FORCEADD GND..1
(-1975 1900);
FORCEPROP 3 LASTPIN (-1975 1950) SIG_NAME GND\g
J 0
(-1965 1960);
DISPLAY 0.659574 (-1965 1960);
PAINT MONO (-1965 1960);
DISPLAY INVISIBLE (-1965 1960);
FORCEPROP 2 LAST CDS_LIB mstr_symbols
J 0
(-1975 1900);
DISPLAY 0.723404 (-1975 1900);
DISPLAY INVISIBLE (-1975 1900);
FORCEPROP 1 LAST SIZE 1B
J 0
(-1900 1850);
DISPLAY 0.851064 (-1900 1850);
PAINT GREEN (-1900 1850);
DISPLAY INVISIBLE (-1900 1850);
FORCEPROP 1 LAST BODY_TYPE PLUMBING
J 0
(-2020 1857);
DISPLAY 0.340426 (-2020 1857);
PAINT GREEN (-2020 1857);
DISPLAY INVISIBLE (-2020 1857);
FORCEPROP 1 LAST PATH I130
J 0
(-1900 1900);
DISPLAY 0.872340 (-1900 1900);
PAINT AQUA (-1900 1900);
DISPLAY INVISIBLE (-1900 1900);
FORCEPROP 1 LAST VOLTAGE 0.0
J 0
(-2020 1857);
DISPLAY 0.723404 (-2020 1857);
PAINT SKYBLUE (-2020 1857);
DISPLAY INVISIBLE (-2020 1857);
FORCEPROP 1 LAST HDL_POWER GND
J 0
(-1975 2050);
DISPLAY 0.851064 (-1975 2050);
PAINT GREEN (-1975 2050);
DISPLAY INVISIBLE (-1975 2050);
FORCEADD OFFPAGE..1
(-7925 4300);
FORCEPROP 2 LAST $XR0 16 
J 0
(-8176 4300);
DISPLAY 0.638298 (-8176 4300);
PAINT MONO (-8176 4300);
FORCEPROP 2 LAST PATH I14
J 0
(-7875 4375);
DISPLAY 1.021277 (-7875 4375);
DISPLAY INVISIBLE (-7875 4375);
FORCEPROP 1 LAST COMMENT_BODY TRUE
J 0
(-7800 4200);
DISPLAY 0.872340 (-7800 4200);
PAINT GREEN (-7800 4200);
DISPLAY INVISIBLE (-7800 4200);
FORCEPROP 1 LAST OFFPAGE TRUE
J 0
(-7600 4175);
DISPLAY 0.872340 (-7600 4175);
PAINT GREEN (-7600 4175);
DISPLAY INVISIBLE (-7600 4175);
FORCEPROP 2 LAST CDS_LIB mstr_standard
J 0
(-7925 4300);
DISPLAY 0.723404 (-7925 4300);
PAINT MONO (-7925 4300);
DISPLAY INVISIBLE (-7925 4300);
FORCEADD GND..1
(-375 1700);
FORCEPROP 3 LASTPIN (-375 1750) SIG_NAME GND\g
J 0
(-365 1760);
DISPLAY 0.659574 (-365 1760);
PAINT MONO (-365 1760);
DISPLAY INVISIBLE (-365 1760);
FORCEPROP 1 LAST SIZE 1B
J 0
(-300 1650);
DISPLAY 0.851064 (-300 1650);
PAINT GREEN (-300 1650);
DISPLAY INVISIBLE (-300 1650);
FORCEPROP 2 LAST CDS_LIB mstr_symbols
J 0
(-375 1700);
DISPLAY 0.723404 (-375 1700);
DISPLAY INVISIBLE (-375 1700);
FORCEPROP 1 LAST BODY_TYPE PLUMBING
J 0
(-420 1657);
DISPLAY 0.340426 (-420 1657);
PAINT GREEN (-420 1657);
DISPLAY INVISIBLE (-420 1657);
FORCEPROP 1 LAST PATH I146
J 0
(-300 1700);
DISPLAY 0.872340 (-300 1700);
PAINT AQUA (-300 1700);
DISPLAY INVISIBLE (-300 1700);
FORCEPROP 1 LAST VOLTAGE 0.0
J 0
(-420 1657);
DISPLAY 0.723404 (-420 1657);
PAINT SKYBLUE (-420 1657);
DISPLAY INVISIBLE (-420 1657);
FORCEPROP 1 LAST HDL_POWER GND
J 0
(-375 1850);
DISPLAY 0.851064 (-375 1850);
PAINT GREEN (-375 1850);
DISPLAY INVISIBLE (-375 1850);
FORCEADD OFFPAGE..1
(-7925 4150);
FORCEPROP 2 LAST $XR0 16 
J 0
(-8176 4150);
DISPLAY 0.638298 (-8176 4150);
PAINT MONO (-8176 4150);
FORCEPROP 2 LAST PATH I15
J 0
(-8175 4200);
DISPLAY 1.021277 (-8175 4200);
DISPLAY INVISIBLE (-8175 4200);
FORCEPROP 1 LAST COMMENT_BODY TRUE
J 0
(-7800 4050);
DISPLAY 0.872340 (-7800 4050);
PAINT GREEN (-7800 4050);
DISPLAY INVISIBLE (-7800 4050);
FORCEPROP 1 LAST OFFPAGE TRUE
J 0
(-7600 4025);
DISPLAY 0.872340 (-7600 4025);
PAINT GREEN (-7600 4025);
DISPLAY INVISIBLE (-7600 4025);
FORCEPROP 2 LAST CDS_LIB mstr_standard
J 0
(-7925 4150);
DISPLAY 0.723404 (-7925 4150);
PAINT MONO (-7925 4150);
DISPLAY INVISIBLE (-7925 4150);
FORCEADD OFFPAGE..1
(-7925 4550);
FORCEPROP 2 LAST $XR0 16 
J 0
(-8176 4550);
DISPLAY 0.638298 (-8176 4550);
PAINT MONO (-8176 4550);
FORCEPROP 2 LAST PATH I16
J 0
(-8175 4600);
DISPLAY 1.021277 (-8175 4600);
DISPLAY INVISIBLE (-8175 4600);
FORCEPROP 1 LAST COMMENT_BODY TRUE
J 0
(-7800 4450);
DISPLAY 0.872340 (-7800 4450);
PAINT GREEN (-7800 4450);
DISPLAY INVISIBLE (-7800 4450);
FORCEPROP 1 LAST OFFPAGE TRUE
J 0
(-7600 4425);
DISPLAY 0.872340 (-7600 4425);
PAINT GREEN (-7600 4425);
DISPLAY INVISIBLE (-7600 4425);
FORCEPROP 2 LAST CDS_LIB mstr_standard
J 0
(-7925 4550);
DISPLAY 0.808511 (-7925 4550);
DISPLAY INVISIBLE (-7925 4550);
FORCEADD OFFPAGE..1
(-7925 4400);
FORCEPROP 2 LAST $XR0 16 
J 0
(-8176 4400);
DISPLAY 0.638298 (-8176 4400);
PAINT MONO (-8176 4400);
FORCEPROP 2 LAST PATH I17
J 0
(-8175 4450);
DISPLAY 1.021277 (-8175 4450);
DISPLAY INVISIBLE (-8175 4450);
FORCEPROP 1 LAST COMMENT_BODY TRUE
J 0
(-7800 4300);
DISPLAY 0.872340 (-7800 4300);
PAINT GREEN (-7800 4300);
DISPLAY INVISIBLE (-7800 4300);
FORCEPROP 1 LAST OFFPAGE TRUE
J 0
(-7600 4275);
DISPLAY 0.872340 (-7600 4275);
PAINT GREEN (-7600 4275);
DISPLAY INVISIBLE (-7600 4275);
FORCEPROP 2 LAST CDS_LIB mstr_standard
J 0
(-7925 4400);
DISPLAY 0.808511 (-7925 4400);
DISPLAY INVISIBLE (-7925 4400);
FORCEADD SCONN288_DDR506112002KQ..3
(-1175 3650);
FORCEPROP 1 LAST LOCATION J16
J 0
(-1625 5625);
DISPLAY 0.468085 (-1625 5625);
PAINT SKYBLUE (-1625 5625);
FORCEPROP 0 LAST $SEC 3
J 0
(-1625 5775);
DISPLAY 0.680851 (-1625 5775);
PAINT MONO (-1625 5775);
DISPLAY INVISIBLE (-1625 5775);
FORCEPROP 0 LAST CDS_SEC 3
J 0
(-1625 5775);
DISPLAY 0.680851 (-1625 5775);
DISPLAY INVISIBLE (-1625 5775);
FORCEPROP 0 LASTPIN (-575 2050) $PN G1
J 0
(-565 2060);
DISPLAY 0.680851 (-565 2060);
PAINT MONO (-565 2060);
FORCEPROP 0 LASTPIN (-575 2000) $PN G2
J 0
(-565 2010);
DISPLAY 0.680851 (-565 2010);
PAINT MONO (-565 2010);
FORCEPROP 0 LASTPIN (-575 1950) $PN G3
J 0
(-565 1960);
DISPLAY 0.680851 (-565 1960);
PAINT MONO (-565 1960);
FORCEPROP 0 LASTPIN (-1775 5200) $PN 1
J 2
(-1785 5210);
DISPLAY 0.680851 (-1785 5210);
PAINT MONO (-1785 5210);
FORCEPROP 0 LASTPIN (-1775 5250) $PN 145
J 2
(-1785 5260);
DISPLAY 0.680851 (-1785 5260);
PAINT MONO (-1785 5260);
FORCEPROP 0 LASTPIN (-1775 5300) $PN 146
J 2
(-1785 5310);
DISPLAY 0.680851 (-1785 5310);
PAINT MONO (-1785 5310);
FORCEPROP 0 LASTPIN (-575 2150) $PN 6
J 0
(-565 2160);
DISPLAY 0.680851 (-565 2160);
PAINT MONO (-565 2160);
FORCEPROP 0 LASTPIN (-575 2200) $PN 8
J 0
(-565 2210);
DISPLAY 0.680851 (-565 2210);
PAINT MONO (-565 2210);
FORCEPROP 0 LASTPIN (-575 2250) $PN 10
J 0
(-565 2260);
DISPLAY 0.680851 (-565 2260);
PAINT MONO (-565 2260);
FORCEPROP 0 LASTPIN (-575 2300) $PN 13
J 0
(-565 2310);
DISPLAY 0.680851 (-565 2310);
PAINT MONO (-565 2310);
FORCEPROP 0 LASTPIN (-575 2350) $PN 15
J 0
(-565 2360);
DISPLAY 0.680851 (-565 2360);
PAINT MONO (-565 2360);
FORCEPROP 0 LASTPIN (-575 2400) $PN 17
J 0
(-565 2410);
DISPLAY 0.680851 (-565 2410);
PAINT MONO (-565 2410);
FORCEPROP 0 LASTPIN (-575 2450) $PN 19
J 0
(-565 2460);
DISPLAY 0.680851 (-565 2460);
PAINT MONO (-565 2460);
FORCEPROP 0 LASTPIN (-575 2500) $PN 21
J 0
(-565 2510);
DISPLAY 0.680851 (-565 2510);
PAINT MONO (-565 2510);
FORCEPROP 0 LASTPIN (-575 2550) $PN 24
J 0
(-565 2560);
DISPLAY 0.680851 (-565 2560);
PAINT MONO (-565 2560);
FORCEPROP 0 LASTPIN (-575 2600) $PN 26
J 0
(-565 2610);
DISPLAY 0.680851 (-565 2610);
PAINT MONO (-565 2610);
FORCEPROP 0 LASTPIN (-575 2650) $PN 28
J 0
(-565 2660);
DISPLAY 0.680851 (-565 2660);
PAINT MONO (-565 2660);
FORCEPROP 0 LASTPIN (-575 2700) $PN 30
J 0
(-565 2710);
DISPLAY 0.680851 (-565 2710);
PAINT MONO (-565 2710);
FORCEPROP 0 LASTPIN (-575 2750) $PN 32
J 0
(-565 2760);
DISPLAY 0.680851 (-565 2760);
PAINT MONO (-565 2760);
FORCEPROP 0 LASTPIN (-575 2800) $PN 35
J 0
(-565 2810);
DISPLAY 0.680851 (-565 2810);
PAINT MONO (-565 2810);
FORCEPROP 0 LASTPIN (-575 2850) $PN 37
J 0
(-565 2860);
DISPLAY 0.680851 (-565 2860);
PAINT MONO (-565 2860);
FORCEPROP 0 LASTPIN (-575 2900) $PN 39
J 0
(-565 2910);
DISPLAY 0.680851 (-565 2910);
PAINT MONO (-565 2910);
FORCEPROP 0 LASTPIN (-575 2950) $PN 41
J 0
(-565 2960);
DISPLAY 0.680851 (-565 2960);
PAINT MONO (-565 2960);
FORCEPROP 0 LASTPIN (-575 3000) $PN 43
J 0
(-565 3010);
DISPLAY 0.680851 (-565 3010);
PAINT MONO (-565 3010);
FORCEPROP 0 LASTPIN (-575 3050) $PN 46
J 0
(-565 3060);
DISPLAY 0.680851 (-565 3060);
PAINT MONO (-565 3060);
FORCEPROP 0 LASTPIN (-575 3100) $PN 48
J 0
(-565 3110);
DISPLAY 0.680851 (-565 3110);
PAINT MONO (-565 3110);
FORCEPROP 0 LASTPIN (-575 3150) $PN 50
J 0
(-565 3160);
DISPLAY 0.680851 (-565 3160);
PAINT MONO (-565 3160);
FORCEPROP 0 LASTPIN (-575 3200) $PN 52
J 0
(-565 3210);
DISPLAY 0.680851 (-565 3210);
PAINT MONO (-565 3210);
FORCEPROP 0 LASTPIN (-575 3250) $PN 54
J 0
(-565 3260);
DISPLAY 0.680851 (-565 3260);
PAINT MONO (-565 3260);
FORCEPROP 0 LASTPIN (-575 3300) $PN 57
J 0
(-565 3310);
DISPLAY 0.680851 (-565 3310);
PAINT MONO (-565 3310);
FORCEPROP 0 LASTPIN (-575 3350) $PN 59
J 0
(-565 3360);
DISPLAY 0.680851 (-565 3360);
PAINT MONO (-565 3360);
FORCEPROP 0 LASTPIN (-575 3400) $PN 61
J 0
(-565 3410);
DISPLAY 0.680851 (-565 3410);
PAINT MONO (-565 3410);
FORCEPROP 0 LASTPIN (-575 3450) $PN 63
J 0
(-565 3460);
DISPLAY 0.680851 (-565 3460);
PAINT MONO (-565 3460);
FORCEPROP 0 LASTPIN (-575 3500) $PN 65
J 0
(-565 3510);
DISPLAY 0.680851 (-565 3510);
PAINT MONO (-565 3510);
FORCEPROP 0 LASTPIN (-575 3550) $PN 67
J 0
(-565 3560);
DISPLAY 0.680851 (-565 3560);
PAINT MONO (-565 3560);
FORCEPROP 0 LASTPIN (-575 3600) $PN 69
J 0
(-565 3610);
DISPLAY 0.680851 (-565 3610);
PAINT MONO (-565 3610);
FORCEPROP 0 LASTPIN (-575 3650) $PN 71
J 0
(-565 3660);
DISPLAY 0.680851 (-565 3660);
PAINT MONO (-565 3660);
FORCEPROP 0 LASTPIN (-575 3700) $PN 73
J 0
(-565 3710);
DISPLAY 0.680851 (-565 3710);
PAINT MONO (-565 3710);
FORCEPROP 0 LASTPIN (-575 3750) $PN 75
J 0
(-565 3760);
DISPLAY 0.680851 (-565 3760);
PAINT MONO (-565 3760);
FORCEPROP 0 LASTPIN (-575 3800) $PN 77
J 0
(-565 3810);
DISPLAY 0.680851 (-565 3810);
PAINT MONO (-565 3810);
FORCEPROP 0 LASTPIN (-575 3850) $PN 79
J 0
(-565 3860);
DISPLAY 0.680851 (-565 3860);
PAINT MONO (-565 3860);
FORCEPROP 0 LASTPIN (-575 3900) $PN 81
J 0
(-565 3910);
DISPLAY 0.680851 (-565 3910);
PAINT MONO (-565 3910);
FORCEPROP 0 LASTPIN (-575 3950) $PN 83
J 0
(-565 3960);
DISPLAY 0.680851 (-565 3960);
PAINT MONO (-565 3960);
FORCEPROP 0 LASTPIN (-575 4000) $PN 85
J 0
(-565 4010);
DISPLAY 0.680851 (-565 4010);
PAINT MONO (-565 4010);
FORCEPROP 0 LASTPIN (-575 4050) $PN 88
J 0
(-565 4060);
DISPLAY 0.680851 (-565 4060);
PAINT MONO (-565 4060);
FORCEPROP 0 LASTPIN (-575 4100) $PN 90
J 0
(-565 4110);
DISPLAY 0.680851 (-565 4110);
PAINT MONO (-565 4110);
FORCEPROP 0 LASTPIN (-575 4150) $PN 92
J 0
(-565 4160);
DISPLAY 0.680851 (-565 4160);
PAINT MONO (-565 4160);
FORCEPROP 0 LASTPIN (-575 4200) $PN 95
J 0
(-565 4210);
DISPLAY 0.680851 (-565 4210);
PAINT MONO (-565 4210);
FORCEPROP 0 LASTPIN (-575 4250) $PN 97
J 0
(-565 4260);
DISPLAY 0.680851 (-565 4260);
PAINT MONO (-565 4260);
FORCEPROP 0 LASTPIN (-575 4300) $PN 99
J 0
(-565 4310);
DISPLAY 0.680851 (-565 4310);
PAINT MONO (-565 4310);
FORCEPROP 0 LASTPIN (-575 4350) $PN 101
J 0
(-565 4360);
DISPLAY 0.680851 (-565 4360);
PAINT MONO (-565 4360);
FORCEPROP 0 LASTPIN (-575 4400) $PN 103
J 0
(-565 4410);
DISPLAY 0.680851 (-565 4410);
PAINT MONO (-565 4410);
FORCEPROP 0 LASTPIN (-575 4450) $PN 106
J 0
(-565 4460);
DISPLAY 0.680851 (-565 4460);
PAINT MONO (-565 4460);
FORCEPROP 0 LASTPIN (-575 4500) $PN 108
J 0
(-565 4510);
DISPLAY 0.680851 (-565 4510);
PAINT MONO (-565 4510);
FORCEPROP 0 LASTPIN (-575 4550) $PN 110
J 0
(-565 4560);
DISPLAY 0.680851 (-565 4560);
PAINT MONO (-565 4560);
FORCEPROP 0 LASTPIN (-575 4600) $PN 112
J 0
(-565 4610);
DISPLAY 0.680851 (-565 4610);
PAINT MONO (-565 4610);
FORCEPROP 0 LASTPIN (-575 4650) $PN 114
J 0
(-565 4660);
DISPLAY 0.680851 (-565 4660);
PAINT MONO (-565 4660);
FORCEPROP 0 LASTPIN (-575 4700) $PN 117
J 0
(-565 4710);
DISPLAY 0.680851 (-565 4710);
PAINT MONO (-565 4710);
FORCEPROP 0 LASTPIN (-575 4750) $PN 119
J 0
(-565 4760);
DISPLAY 0.680851 (-565 4760);
PAINT MONO (-565 4760);
FORCEPROP 0 LASTPIN (-575 4800) $PN 121
J 0
(-565 4810);
DISPLAY 0.680851 (-565 4810);
PAINT MONO (-565 4810);
FORCEPROP 0 LASTPIN (-575 4850) $PN 123
J 0
(-565 4860);
DISPLAY 0.680851 (-565 4860);
PAINT MONO (-565 4860);
FORCEPROP 0 LASTPIN (-575 4900) $PN 125
J 0
(-565 4910);
DISPLAY 0.680851 (-565 4910);
PAINT MONO (-565 4910);
FORCEPROP 0 LASTPIN (-575 4950) $PN 128
J 0
(-565 4960);
DISPLAY 0.680851 (-565 4960);
PAINT MONO (-565 4960);
FORCEPROP 0 LASTPIN (-575 5000) $PN 130
J 0
(-565 5010);
DISPLAY 0.680851 (-565 5010);
PAINT MONO (-565 5010);
FORCEPROP 0 LASTPIN (-575 5050) $PN 132
J 0
(-565 5060);
DISPLAY 0.680851 (-565 5060);
PAINT MONO (-565 5060);
FORCEPROP 0 LASTPIN (-575 5100) $PN 134
J 0
(-565 5110);
DISPLAY 0.680851 (-565 5110);
PAINT MONO (-565 5110);
FORCEPROP 0 LASTPIN (-575 5150) $PN 136
J 0
(-565 5160);
DISPLAY 0.680851 (-565 5160);
PAINT MONO (-565 5160);
FORCEPROP 0 LASTPIN (-575 5200) $PN 139
J 0
(-565 5210);
DISPLAY 0.680851 (-565 5210);
PAINT MONO (-565 5210);
FORCEPROP 0 LASTPIN (-575 5250) $PN 141
J 0
(-565 5260);
DISPLAY 0.680851 (-565 5260);
PAINT MONO (-565 5260);
FORCEPROP 0 LASTPIN (-575 5300) $PN 143
J 0
(-565 5310);
DISPLAY 0.680851 (-565 5310);
PAINT MONO (-565 5310);
FORCEPROP 0 LASTPIN (-1775 2050) $PN 151
J 2
(-1785 2060);
DISPLAY 0.680851 (-1785 2060);
PAINT MONO (-1785 2060);
FORCEPROP 0 LASTPIN (-1775 2100) $PN 153
J 2
(-1785 2110);
DISPLAY 0.680851 (-1785 2110);
PAINT MONO (-1785 2110);
FORCEPROP 0 LASTPIN (-1775 2150) $PN 155
J 2
(-1785 2160);
DISPLAY 0.680851 (-1785 2160);
PAINT MONO (-1785 2160);
FORCEPROP 0 LASTPIN (-1775 2200) $PN 158
J 2
(-1785 2210);
DISPLAY 0.680851 (-1785 2210);
PAINT MONO (-1785 2210);
FORCEPROP 0 LASTPIN (-1775 2250) $PN 160
J 2
(-1785 2260);
DISPLAY 0.680851 (-1785 2260);
PAINT MONO (-1785 2260);
FORCEPROP 0 LASTPIN (-1775 2300) $PN 162
J 2
(-1785 2310);
DISPLAY 0.680851 (-1785 2310);
PAINT MONO (-1785 2310);
FORCEPROP 0 LASTPIN (-1775 2350) $PN 164
J 2
(-1785 2360);
DISPLAY 0.680851 (-1785 2360);
PAINT MONO (-1785 2360);
FORCEPROP 0 LASTPIN (-1775 2400) $PN 166
J 2
(-1785 2410);
DISPLAY 0.680851 (-1785 2410);
PAINT MONO (-1785 2410);
FORCEPROP 0 LASTPIN (-1775 2450) $PN 169
J 2
(-1785 2460);
DISPLAY 0.680851 (-1785 2460);
PAINT MONO (-1785 2460);
FORCEPROP 0 LASTPIN (-1775 2500) $PN 171
J 2
(-1785 2510);
DISPLAY 0.680851 (-1785 2510);
PAINT MONO (-1785 2510);
FORCEPROP 0 LASTPIN (-1775 2550) $PN 173
J 2
(-1785 2560);
DISPLAY 0.680851 (-1785 2560);
PAINT MONO (-1785 2560);
FORCEPROP 0 LASTPIN (-1775 2600) $PN 175
J 2
(-1785 2610);
DISPLAY 0.680851 (-1785 2610);
PAINT MONO (-1785 2610);
FORCEPROP 0 LASTPIN (-1775 2650) $PN 177
J 2
(-1785 2660);
DISPLAY 0.680851 (-1785 2660);
PAINT MONO (-1785 2660);
FORCEPROP 0 LASTPIN (-1775 2700) $PN 180
J 2
(-1785 2710);
DISPLAY 0.680851 (-1785 2710);
PAINT MONO (-1785 2710);
FORCEPROP 0 LASTPIN (-1775 2750) $PN 182
J 2
(-1785 2760);
DISPLAY 0.680851 (-1785 2760);
PAINT MONO (-1785 2760);
FORCEPROP 0 LASTPIN (-1775 2800) $PN 184
J 2
(-1785 2810);
DISPLAY 0.680851 (-1785 2810);
PAINT MONO (-1785 2810);
FORCEPROP 0 LASTPIN (-1775 2850) $PN 186
J 2
(-1785 2860);
DISPLAY 0.680851 (-1785 2860);
PAINT MONO (-1785 2860);
FORCEPROP 0 LASTPIN (-1775 2900) $PN 188
J 2
(-1785 2910);
DISPLAY 0.680851 (-1785 2910);
PAINT MONO (-1785 2910);
FORCEPROP 0 LASTPIN (-1775 2950) $PN 191
J 2
(-1785 2960);
DISPLAY 0.680851 (-1785 2960);
PAINT MONO (-1785 2960);
FORCEPROP 0 LASTPIN (-1775 3000) $PN 193
J 2
(-1785 3010);
DISPLAY 0.680851 (-1785 3010);
PAINT MONO (-1785 3010);
FORCEPROP 0 LASTPIN (-1775 3050) $PN 195
J 2
(-1785 3060);
DISPLAY 0.680851 (-1785 3060);
PAINT MONO (-1785 3060);
FORCEPROP 0 LASTPIN (-1775 3100) $PN 197
J 2
(-1785 3110);
DISPLAY 0.680851 (-1785 3110);
PAINT MONO (-1785 3110);
FORCEPROP 0 LASTPIN (-1775 3150) $PN 199
J 2
(-1785 3160);
DISPLAY 0.680851 (-1785 3160);
PAINT MONO (-1785 3160);
FORCEPROP 0 LASTPIN (-1775 3200) $PN 202
J 2
(-1785 3210);
DISPLAY 0.680851 (-1785 3210);
PAINT MONO (-1785 3210);
FORCEPROP 0 LASTPIN (-1775 3250) $PN 204
J 2
(-1785 3260);
DISPLAY 0.680851 (-1785 3260);
PAINT MONO (-1785 3260);
FORCEPROP 0 LASTPIN (-1775 3300) $PN 206
J 2
(-1785 3310);
DISPLAY 0.680851 (-1785 3310);
PAINT MONO (-1785 3310);
FORCEPROP 0 LASTPIN (-1775 3350) $PN 208
J 2
(-1785 3360);
DISPLAY 0.680851 (-1785 3360);
PAINT MONO (-1785 3360);
FORCEPROP 0 LASTPIN (-1775 3400) $PN 210
J 2
(-1785 3410);
DISPLAY 0.680851 (-1785 3410);
PAINT MONO (-1785 3410);
FORCEPROP 0 LASTPIN (-1775 3450) $PN 212
J 2
(-1785 3460);
DISPLAY 0.680851 (-1785 3460);
PAINT MONO (-1785 3460);
FORCEPROP 0 LASTPIN (-1775 3500) $PN 214
J 2
(-1785 3510);
DISPLAY 0.680851 (-1785 3510);
PAINT MONO (-1785 3510);
FORCEPROP 0 LASTPIN (-1775 3550) $PN 216
J 2
(-1785 3560);
DISPLAY 0.680851 (-1785 3560);
PAINT MONO (-1785 3560);
FORCEPROP 0 LASTPIN (-1775 3600) $PN 219
J 2
(-1785 3610);
DISPLAY 0.680851 (-1785 3610);
PAINT MONO (-1785 3610);
FORCEPROP 0 LASTPIN (-1775 3650) $PN 222
J 2
(-1785 3660);
DISPLAY 0.680851 (-1785 3660);
PAINT MONO (-1785 3660);
FORCEPROP 0 LASTPIN (-1775 3700) $PN 224
J 2
(-1785 3710);
DISPLAY 0.680851 (-1785 3710);
PAINT MONO (-1785 3710);
FORCEPROP 0 LASTPIN (-1775 3750) $PN 226
J 2
(-1785 3760);
DISPLAY 0.680851 (-1785 3760);
PAINT MONO (-1785 3760);
FORCEPROP 0 LASTPIN (-1775 3800) $PN 228
J 2
(-1785 3810);
DISPLAY 0.680851 (-1785 3810);
PAINT MONO (-1785 3810);
FORCEPROP 0 LASTPIN (-1775 3850) $PN 230
J 2
(-1785 3860);
DISPLAY 0.680851 (-1785 3860);
PAINT MONO (-1785 3860);
FORCEPROP 0 LASTPIN (-1775 3900) $PN 233
J 2
(-1785 3910);
DISPLAY 0.680851 (-1785 3910);
PAINT MONO (-1785 3910);
FORCEPROP 0 LASTPIN (-1775 3950) $PN 235
J 2
(-1785 3960);
DISPLAY 0.680851 (-1785 3960);
PAINT MONO (-1785 3960);
FORCEPROP 0 LASTPIN (-1775 4000) $PN 237
J 2
(-1785 4010);
DISPLAY 0.680851 (-1785 4010);
PAINT MONO (-1785 4010);
FORCEPROP 0 LASTPIN (-1775 4050) $PN 240
J 2
(-1785 4060);
DISPLAY 0.680851 (-1785 4060);
PAINT MONO (-1785 4060);
FORCEPROP 0 LASTPIN (-1775 4100) $PN 242
J 2
(-1785 4110);
DISPLAY 0.680851 (-1785 4110);
PAINT MONO (-1785 4110);
FORCEPROP 0 LASTPIN (-1775 4150) $PN 244
J 2
(-1785 4160);
DISPLAY 0.680851 (-1785 4160);
PAINT MONO (-1785 4160);
FORCEPROP 0 LASTPIN (-1775 4200) $PN 246
J 2
(-1785 4210);
DISPLAY 0.680851 (-1785 4210);
PAINT MONO (-1785 4210);
FORCEPROP 0 LASTPIN (-1775 4250) $PN 248
J 2
(-1785 4260);
DISPLAY 0.680851 (-1785 4260);
PAINT MONO (-1785 4260);
FORCEPROP 0 LASTPIN (-1775 4300) $PN 251
J 2
(-1785 4310);
DISPLAY 0.680851 (-1785 4310);
PAINT MONO (-1785 4310);
FORCEPROP 0 LASTPIN (-1775 4350) $PN 253
J 2
(-1785 4360);
DISPLAY 0.680851 (-1785 4360);
PAINT MONO (-1785 4360);
FORCEPROP 0 LASTPIN (-1775 4400) $PN 255
J 2
(-1785 4410);
DISPLAY 0.680851 (-1785 4410);
PAINT MONO (-1785 4410);
FORCEPROP 0 LASTPIN (-1775 4450) $PN 257
J 2
(-1785 4460);
DISPLAY 0.680851 (-1785 4460);
PAINT MONO (-1785 4460);
FORCEPROP 0 LASTPIN (-1775 4500) $PN 259
J 2
(-1785 4510);
DISPLAY 0.680851 (-1785 4510);
PAINT MONO (-1785 4510);
FORCEPROP 0 LASTPIN (-1775 4550) $PN 262
J 2
(-1785 4560);
DISPLAY 0.680851 (-1785 4560);
PAINT MONO (-1785 4560);
FORCEPROP 0 LASTPIN (-1775 4600) $PN 264
J 2
(-1785 4610);
DISPLAY 0.680851 (-1785 4610);
PAINT MONO (-1785 4610);
FORCEPROP 0 LASTPIN (-1775 4650) $PN 266
J 2
(-1785 4660);
DISPLAY 0.680851 (-1785 4660);
PAINT MONO (-1785 4660);
FORCEPROP 0 LASTPIN (-1775 4700) $PN 268
J 2
(-1785 4710);
DISPLAY 0.680851 (-1785 4710);
PAINT MONO (-1785 4710);
FORCEPROP 0 LASTPIN (-1775 4750) $PN 270
J 2
(-1785 4760);
DISPLAY 0.680851 (-1785 4760);
PAINT MONO (-1785 4760);
FORCEPROP 0 LASTPIN (-1775 4800) $PN 273
J 2
(-1785 4810);
DISPLAY 0.680851 (-1785 4810);
PAINT MONO (-1785 4810);
FORCEPROP 0 LASTPIN (-1775 4850) $PN 275
J 2
(-1785 4860);
DISPLAY 0.680851 (-1785 4860);
PAINT MONO (-1785 4860);
FORCEPROP 0 LASTPIN (-1775 4900) $PN 277
J 2
(-1785 4910);
DISPLAY 0.680851 (-1785 4910);
PAINT MONO (-1785 4910);
FORCEPROP 0 LASTPIN (-1775 4950) $PN 279
J 2
(-1785 4960);
DISPLAY 0.680851 (-1785 4960);
PAINT MONO (-1785 4960);
FORCEPROP 0 LASTPIN (-1775 5000) $PN 281
J 2
(-1785 5010);
DISPLAY 0.680851 (-1785 5010);
PAINT MONO (-1785 5010);
FORCEPROP 0 LASTPIN (-1775 5050) $PN 284
J 2
(-1785 5060);
DISPLAY 0.680851 (-1785 5060);
PAINT MONO (-1785 5060);
FORCEPROP 0 LASTPIN (-1775 5100) $PN 286
J 2
(-1785 5110);
DISPLAY 0.680851 (-1785 5110);
PAINT MONO (-1785 5110);
FORCEPROP 0 LASTPIN (-1775 5150) $PN 288
J 2
(-1785 5160);
DISPLAY 0.680851 (-1785 5160);
PAINT MONO (-1785 5160);
FORCEPROP 2 LAST VALUE SCONN288_DDR506112002KQ
J 0
(-1625 5675);
DISPLAY 0.489362 (-1625 5675);
PAINT SKYBLUE (-1625 5675);
FORCEPROP 2 LAST PART_TYPE SMLF
J 0
(-1625 5725);
DISPLAY 1.021277 (-1625 5725);
FORCEPROP 1 LAST MATERIAL IO
J 0
(-1625 5475);
DISPLAY 0.468085 (-1625 5475);
PAINT SKYBLUE (-1625 5475);
FORCEPROP 1 LAST PART_NUMBER DFHST8FS479
J 0
(-1625 5550);
DISPLAY 0.468085 (-1625 5550);
PAINT SKYBLUE (-1625 5550);
FORCEPROP 1 LAST CDS_LMAN_SYM_OUTLINE -450,1800,450,-1750
J 0
(-1175 3650);
DISPLAY 0.468085 (-1175 3650);
PAINT GREEN (-1175 3650);
DISPLAY INVISIBLE (-1175 3650);
FORCEPROP 1 LAST PATH I177
J 0
(-1175 3650);
DISPLAY 0.723404 (-1175 3650);
PAINT GREEN (-1175 3650);
DISPLAY INVISIBLE (-1175 3650);
FORCEPROP 1 LAST NEEDS_NO_SIZE TRUE
J 0
(-1175 3650);
DISPLAY 0.723404 (-1175 3650);
PAINT GREEN (-1175 3650);
DISPLAY INVISIBLE (-1175 3650);
FORCEPROP 2 LAST CDS_LIB pure_quanta
J 0
(-1175 3650);
DISPLAY INVISIBLE (-1175 3650);
FORCEADD OFFPAGE..1
(-7925 4450);
FORCEPROP 2 LAST $XR0 16 
J 0
(-8176 4450);
DISPLAY 0.638298 (-8176 4450);
PAINT MONO (-8176 4450);
FORCEPROP 2 LAST PATH I18
J 0
(-8175 4500);
DISPLAY 1.021277 (-8175 4500);
DISPLAY INVISIBLE (-8175 4500);
FORCEPROP 1 LAST COMMENT_BODY TRUE
J 0
(-7800 4350);
DISPLAY 0.872340 (-7800 4350);
PAINT GREEN (-7800 4350);
DISPLAY INVISIBLE (-7800 4350);
FORCEPROP 1 LAST OFFPAGE TRUE
J 0
(-7600 4325);
DISPLAY 0.872340 (-7600 4325);
PAINT GREEN (-7600 4325);
DISPLAY INVISIBLE (-7600 4325);
FORCEPROP 2 LAST CDS_LIB mstr_standard
J 0
(-7925 4450);
DISPLAY 0.723404 (-7925 4450);
PAINT MONO (-7925 4450);
DISPLAY INVISIBLE (-7925 4450);
FORCEADD Q_CAP..1
R 2
(-8500 3225);
FORCEPROP 1 LAST LOCATION C112
J 2
(-8550 3325);
DISPLAY 0.489362 (-8550 3325);
PAINT SKYBLUE (-8550 3325);
FORCEPROP 0 LAST $SEC 1
J 0
(-8550 3375);
DISPLAY 0.680851 (-8550 3375);
PAINT MONO (-8550 3375);
DISPLAY INVISIBLE (-8550 3375);
FORCEPROP 0 LAST CDS_SEC 1
J 0
(-8550 3375);
DISPLAY 1.021277 (-8550 3375);
DISPLAY INVISIBLE (-8550 3375);
FORCEPROP 1 LASTPIN (-8500 3325) $PN 1
J 2
(-8510 3305);
DISPLAY 0.489362 (-8510 3305);
PAINT MONO (-8510 3305);
FORCEPROP 1 LASTPIN (-8500 3125) $PN 2
J 2
(-8510 3105);
DISPLAY 0.489362 (-8510 3105);
PAINT MONO (-8510 3105);
FORCEPROP 1 LAST VOLTAGE 25V
J 2
(-8550 3225);
DISPLAY 0.489362 (-8550 3225);
PAINT SKYBLUE (-8550 3225);
FORCEPROP 1 LAST PART_NUMBER CH4104K1B00
J 2
(-8550 3075);
DISPLAY 0.489362 (-8550 3075);
PAINT SKYBLUE (-8550 3075);
FORCEPROP 1 LAST PACK_TYPE 0402
J 2
(-8550 3025);
DISPLAY 0.489362 (-8550 3025);
PAINT SKYBLUE (-8550 3025);
FORCEPROP 1 LAST MATERIAL X7R
J 2
(-8550 3125);
DISPLAY 0.489362 (-8550 3125);
PAINT SKYBLUE (-8550 3125);
FORCEPROP 1 LAST TOLERANCE 10%
J 2
(-8550 3175);
DISPLAY 0.489362 (-8550 3175);
PAINT SKYBLUE (-8550 3175);
FORCEPROP 1 LAST VALUE 0.1UF
J 2
(-8550 3275);
DISPLAY 0.489362 (-8550 3275);
PAINT SKYBLUE (-8550 3275);
FORCEPROP 2 LAST CDS_LIB pure_quanta
J 0
(-8500 3225);
DISPLAY INVISIBLE (-8500 3225);
FORCEPROP 0 LAST BOM_COST MEM
J 2
(-8555 3370);
DISPLAY 0.595745 (-8555 3370);
PAINT MONO (-8555 3370);
DISPLAY INVISIBLE (-8555 3370);
FORCEPROP 1 LAST PATH I183
J 2
(-8550 3375);
DISPLAY 0.978723 (-8550 3375);
PAINT WHITE (-8550 3375);
DISPLAY INVISIBLE (-8550 3375);
FORCEPROP 0 LAST ROOM MEM_CH_A_CPU0_DIMM1
J 2
(-8555 3370);
DISPLAY 0.595745 (-8555 3370);
PAINT RED (-8555 3370);
DISPLAY INVISIBLE (-8555 3370);
FORCEADD GND..1
(-8500 3000);
FORCEPROP 3 LASTPIN (-8500 3050) SIG_NAME GND\g
J 0
(-8490 3060);
DISPLAY 0.659574 (-8490 3060);
PAINT MONO (-8490 3060);
DISPLAY INVISIBLE (-8490 3060);
FORCEPROP 2 LAST CDS_LIB mstr_symbols
J 0
(-8500 3000);
DISPLAY 0.808511 (-8500 3000);
DISPLAY INVISIBLE (-8500 3000);
FORCEPROP 1 LAST SIZE 1B
J 0
(-8425 2950);
DISPLAY 0.723404 (-8425 2950);
PAINT GREEN (-8425 2950);
DISPLAY INVISIBLE (-8425 2950);
FORCEPROP 2 LAST BOM_COST MEM
J 0
(-8475 3125);
DISPLAY 0.659574 (-8475 3125);
DISPLAY INVISIBLE (-8475 3125);
FORCEPROP 1 LAST BODY_TYPE PLUMBING
J 0
(-8545 2957);
DISPLAY 0.276596 (-8545 2957);
PAINT GREEN (-8545 2957);
DISPLAY INVISIBLE (-8545 2957);
FORCEPROP 1 LAST PATH I184
J 0
(-8425 3000);
DISPLAY 0.872340 (-8425 3000);
PAINT AQUA (-8425 3000);
DISPLAY INVISIBLE (-8425 3000);
FORCEPROP 1 LAST VOLTAGE 0
J 0
(-8520 3095);
DISPLAY 0.829787 (-8520 3095);
PAINT SKYBLUE (-8520 3095);
DISPLAY INVISIBLE (-8520 3095);
FORCEPROP 2 LAST ROOM MEM_EFGH_DECOUPLING_CAPS
J 0
(-8475 3075);
DISPLAY 0.659574 (-8475 3075);
PAINT RED (-8475 3075);
DISPLAY INVISIBLE (-8475 3075);
FORCEPROP 1 LAST HDL_POWER GND
J 0
(-8500 3150);
DISPLAY 0.723404 (-8500 3150);
PAINT GREEN (-8500 3150);
DISPLAY INVISIBLE (-8500 3150);
FORCEADD OFFPAGE..6
(-8900 2150);
FORCEPROP 2 LAST $XR5 81 
J 0
(-9329 2114);
DISPLAY 0.638298 (-9329 2114);
PAINT MONO (-9329 2114);
FORCEPROP 2 LAST $XR4 96 
J 0
(-9239 2114);
DISPLAY 0.638298 (-9239 2114);
PAINT MONO (-9239 2114);
FORCEPROP 2 LAST $XR3 95 
J 0
(-9149 2114);
DISPLAY 0.638298 (-9149 2114);
PAINT MONO (-9149 2114);
FORCEPROP 2 LAST $XR2 94 
J 0
(-9329 2150);
DISPLAY 0.638298 (-9329 2150);
PAINT MONO (-9329 2150);
FORCEPROP 2 LAST $XR1 93 
J 0
(-9239 2150);
DISPLAY 0.638298 (-9239 2150);
PAINT MONO (-9239 2150);
FORCEPROP 2 LAST $XR0 92 
J 0
(-9149 2150);
DISPLAY 0.638298 (-9149 2150);
PAINT MONO (-9149 2150);
FORCEPROP 2 LAST PATH I185
J 0
(-8850 2225);
DISPLAY 1.021277 (-8850 2225);
DISPLAY INVISIBLE (-8850 2225);
FORCEPROP 1 LAST COMMENT_BODY TRUE
J 0
(-8800 2075);
DISPLAY 0.872340 (-8800 2075);
PAINT GREEN (-8800 2075);
DISPLAY INVISIBLE (-8800 2075);
FORCEPROP 1 LAST OFFPAGE TRUE
J 0
(-8575 2025);
DISPLAY 0.872340 (-8575 2025);
PAINT GREEN (-8575 2025);
DISPLAY INVISIBLE (-8575 2025);
FORCEPROP 2 LAST CDS_LIB mstr_standard
J 0
(-8900 2150);
DISPLAY INVISIBLE (-8900 2150);
FORCEADD Q_RES..1
R 2
(-8350 2150);
FORCEPROP 1 LAST LOCATION R297
J 2
(-8300 2200);
DISPLAY 0.489362 (-8300 2200);
PAINT SKYBLUE (-8300 2200);
FORCEPROP 0 LAST $SEC 1
J 0
(-8300 2250);
DISPLAY 0.680851 (-8300 2250);
PAINT MONO (-8300 2250);
DISPLAY INVISIBLE (-8300 2250);
FORCEPROP 0 LAST CDS_SEC 1
J 0
(-8300 2250);
DISPLAY 1.021277 (-8300 2250);
DISPLAY INVISIBLE (-8300 2250);
FORCEPROP 1 LASTPIN (-8250 2150) $PN 1
J 2
(-8262 2162);
DISPLAY 0.489362 (-8262 2162);
PAINT MONO (-8262 2162);
FORCEPROP 1 LASTPIN (-8450 2150) $PN 2
J 2
(-8412 2162);
DISPLAY 0.489362 (-8412 2162);
PAINT MONO (-8412 2162);
FORCEPROP 1 LAST VALUE 0
J 0
(-8350 2100);
DISPLAY 0.489362 (-8350 2100);
PAINT SKYBLUE (-8350 2100);
FORCEPROP 2 LAST CDS_LIB pure_quanta
J 0
(-8350 2150);
DISPLAY INVISIBLE (-8350 2150);
FORCEPROP 2 LAST BOM_COST MEM
J 0
(-8375 2300);
DISPLAY 0.744681 (-8375 2300);
PAINT WHITE (-8375 2300);
DISPLAY INVISIBLE (-8375 2300);
FORCEPROP 1 LAST PATH I186
J 2
(-8300 2300);
DISPLAY 0.978723 (-8300 2300);
PAINT WHITE (-8300 2300);
DISPLAY INVISIBLE (-8300 2300);
FORCEPROP 1 LAST WATTAGE 1/16W
J 0
(-8275 2075);
DISPLAY 0.489362 (-8275 2075);
PAINT SKYBLUE (-8275 2075);
DISPLAY INVISIBLE (-8275 2075);
FORCEPROP 1 LAST MATERIAL CHIP
J 0
(-8525 2125);
DISPLAY 0.489362 (-8525 2125);
PAINT SKYBLUE (-8525 2125);
DISPLAY INVISIBLE (-8525 2125);
FORCEPROP 1 LAST TOLERANCE 5%
J 2
(-8225 2125);
DISPLAY 0.489362 (-8225 2125);
PAINT SKYBLUE (-8225 2125);
DISPLAY INVISIBLE (-8225 2125);
FORCEPROP 1 LAST PART_NUMBER CS00002JB38
J 0
(-8450 2200);
DISPLAY 0.489362 (-8450 2200);
PAINT SKYBLUE (-8450 2200);
DISPLAY INVISIBLE (-8450 2200);
FORCEPROP 1 LAST PACK_TYPE 0402LF
J 0
(-8525 2075);
DISPLAY 0.489362 (-8525 2075);
PAINT SKYBLUE (-8525 2075);
DISPLAY INVISIBLE (-8525 2075);
FORCEPROP 2 LAST ROOM RST_CPU0_PLD_TO_DIMM
J 0
(-8375 2250);
DISPLAY 0.744681 (-8375 2250);
PAINT RED (-8375 2250);
DISPLAY INVISIBLE (-8375 2250);
FORCEADD Q_RES..2
(-8225 2300);
FORCEPROP 1 LAST LOCATION R96
J 0
(-8180 2425);
DISPLAY 0.489362 (-8180 2425);
PAINT SKYBLUE (-8180 2425);
FORCEPROP 0 LAST $SEC 1
J 0
(-8175 2475);
DISPLAY 0.680851 (-8175 2475);
PAINT MONO (-8175 2475);
DISPLAY INVISIBLE (-8175 2475);
FORCEPROP 0 LAST CDS_SEC 1
J 0
(-8175 2475);
DISPLAY 1.021277 (-8175 2475);
DISPLAY INVISIBLE (-8175 2475);
FORCEPROP 1 LASTPIN (-8225 2400) $PN 1
J 0
(-8220 2362);
DISPLAY 0.489362 (-8220 2362);
PAINT MONO (-8220 2362);
FORCEPROP 1 LASTPIN (-8225 2200) $PN 2
J 0
(-8220 2210);
DISPLAY 0.489362 (-8220 2210);
PAINT MONO (-8220 2210);
FORCEPROP 1 LAST WATTAGE 1/16W
J 0
(-8175 2325);
DISPLAY 0.489362 (-8175 2325);
PAINT SKYBLUE (-8175 2325);
FORCEPROP 1 LAST MATERIAL EMPTY
J 0
(-8175 2300);
DISPLAY 0.489362 (-8175 2300);
PAINT RED (-8175 2300);
FORCEPROP 1 LAST TOLERANCE 5%
J 0
(-8175 2350);
DISPLAY 0.489362 (-8175 2350);
PAINT SKYBLUE (-8175 2350);
FORCEPROP 1 LAST VALUE 1K
J 0
(-8180 2375);
DISPLAY 0.489362 (-8180 2375);
PAINT SKYBLUE (-8180 2375);
FORCEPROP 1 LAST PACK_TYPE 0402LF
J 0
(-8175 2250);
DISPLAY 0.489362 (-8175 2250);
PAINT SKYBLUE (-8175 2250);
FORCEPROP 2 LAST CDS_LIB pure_quanta
J 0
(-8225 2300);
DISPLAY INVISIBLE (-8225 2300);
FORCEPROP 2 LAST BOM_COST MEM
J 0
(-8175 2475);
DISPLAY 0.808511 (-8175 2475);
DISPLAY INVISIBLE (-8175 2475);
FORCEPROP 1 LAST PATH I187
J 0
(-8175 2475);
DISPLAY 0.978723 (-8175 2475);
PAINT WHITE (-8175 2475);
DISPLAY INVISIBLE (-8175 2475);
FORCEPROP 1 LAST PART_NUMBER TMP_QCS21002JB34
J 0
(-8175 2275);
DISPLAY 0.489362 (-8175 2275);
PAINT SKYBLUE (-8175 2275);
DISPLAY INVISIBLE (-8175 2275);
FORCEPROP 2 LAST ROOM MEM_CH_A_CPU0_DIMM1
J 0
(-8175 2525);
DISPLAY 0.808511 (-8175 2525);
PAINT RED (-8175 2525);
DISPLAY INVISIBLE (-8175 2525);
FORCEADD VCC_CORE..1
(-8225 2475);
FORCEPROP 3 LASTPIN (-8225 2425) SIG_NAME P3V3_STBY\g
J 0
(-8215 2435);
DISPLAY 0.659574 (-8215 2435);
PAINT MONO (-8215 2435);
DISPLAY INVISIBLE (-8215 2435);
FORCEPROP 1 LAST HDL_POWER P3V3_STBY
J 1
(-8225 2525);
DISPLAY 0.489362 (-8225 2525);
PAINT GREEN (-8225 2525);
FORCEPROP 2 LAST CDS_LIB mstr_symbols
J 0
(-8225 2475);
DISPLAY INVISIBLE (-8225 2475);
FORCEPROP 1 LAST PATH I188
J 0
(-8175 2500);
DISPLAY 0.872340 (-8175 2500);
PAINT AQUA (-8175 2500);
DISPLAY INVISIBLE (-8175 2500);
FORCEPROP 0 LAST VOLTAGE 3.3
J 0
(-8500 2625);
DISPLAY 1.021277 (-8500 2625);
PAINT SKYBLUE (-8500 2625);
DISPLAY INVISIBLE (-8500 2625);
FORCEPROP 2 LAST ROOM PVCCINFAON_CPU0_CTRL
J 0
(-8225 2575);
DISPLAY 0.808511 (-8225 2575);
PAINT RED (-8225 2575);
DISPLAY INVISIBLE (-8225 2575);
FORCEADD VCC_CORE..1
(-8475 2475);
FORCEPROP 3 LASTPIN (-8475 2425) SIG_NAME P3V3_STBY\g
J 0
(-8465 2435);
DISPLAY 0.659574 (-8465 2435);
PAINT MONO (-8465 2435);
DISPLAY INVISIBLE (-8465 2435);
FORCEPROP 1 LAST HDL_POWER P3V3_STBY
J 1
(-8475 2525);
DISPLAY 0.489362 (-8475 2525);
PAINT GREEN (-8475 2525);
FORCEPROP 2 LAST CDS_LIB mstr_symbols
J 0
(-8475 2475);
DISPLAY INVISIBLE (-8475 2475);
FORCEPROP 1 LAST PATH I189
J 0
(-8425 2500);
DISPLAY 0.872340 (-8425 2500);
PAINT AQUA (-8425 2500);
DISPLAY INVISIBLE (-8425 2500);
FORCEPROP 0 LAST VOLTAGE 3.3
J 0
(-8750 2625);
DISPLAY 1.021277 (-8750 2625);
PAINT SKYBLUE (-8750 2625);
DISPLAY INVISIBLE (-8750 2625);
FORCEPROP 2 LAST ROOM PVCCINFAON_CPU0_CTRL
J 0
(-8475 2575);
DISPLAY 0.808511 (-8475 2575);
PAINT RED (-8475 2575);
DISPLAY INVISIBLE (-8475 2575);
FORCEADD OFFPAGE..1
(-7925 4600);
FORCEPROP 2 LAST $XR0 16 
J 0
(-8176 4600);
DISPLAY 0.638298 (-8176 4600);
PAINT MONO (-8176 4600);
FORCEPROP 2 LAST PATH I19
J 0
(-8175 4650);
DISPLAY 1.021277 (-8175 4650);
DISPLAY INVISIBLE (-8175 4650);
FORCEPROP 1 LAST COMMENT_BODY TRUE
J 0
(-7800 4500);
DISPLAY 0.872340 (-7800 4500);
PAINT GREEN (-7800 4500);
DISPLAY INVISIBLE (-7800 4500);
FORCEPROP 1 LAST OFFPAGE TRUE
J 0
(-7600 4475);
DISPLAY 0.872340 (-7600 4475);
PAINT GREEN (-7600 4475);
DISPLAY INVISIBLE (-7600 4475);
FORCEPROP 2 LAST CDS_LIB mstr_standard
J 0
(-7925 4600);
DISPLAY 0.723404 (-7925 4600);
PAINT MONO (-7925 4600);
DISPLAY INVISIBLE (-7925 4600);
FORCEADD Q_RES..2
R 2
(-8475 2300);
FORCEPROP 1 LAST LOCATION R95
J 2
(-8520 2425);
DISPLAY 0.489362 (-8520 2425);
PAINT SKYBLUE (-8520 2425);
FORCEPROP 0 LAST $SEC 1
J 0
(-8500 2475);
DISPLAY 0.680851 (-8500 2475);
PAINT MONO (-8500 2475);
DISPLAY INVISIBLE (-8500 2475);
FORCEPROP 0 LAST CDS_SEC 1
J 0
(-8500 2475);
DISPLAY 1.021277 (-8500 2475);
DISPLAY INVISIBLE (-8500 2475);
FORCEPROP 1 LASTPIN (-8475 2400) $PN 1
J 2
(-8480 2362);
DISPLAY 0.489362 (-8480 2362);
PAINT MONO (-8480 2362);
FORCEPROP 1 LASTPIN (-8475 2200) $PN 2
J 2
(-8480 2210);
DISPLAY 0.489362 (-8480 2210);
PAINT MONO (-8480 2210);
FORCEPROP 1 LAST WATTAGE 1/16W
J 2
(-8525 2325);
DISPLAY 0.489362 (-8525 2325);
PAINT SKYBLUE (-8525 2325);
FORCEPROP 1 LAST MATERIAL CHIP
J 2
(-8525 2300);
DISPLAY 0.489362 (-8525 2300);
PAINT SKYBLUE (-8525 2300);
FORCEPROP 1 LAST TOLERANCE 5%
J 2
(-8525 2350);
DISPLAY 0.489362 (-8525 2350);
PAINT SKYBLUE (-8525 2350);
FORCEPROP 1 LAST VALUE 1K
J 2
(-8520 2375);
DISPLAY 0.489362 (-8520 2375);
PAINT SKYBLUE (-8520 2375);
FORCEPROP 1 LAST PACK_TYPE 0402LF
J 2
(-8525 2250);
DISPLAY 0.489362 (-8525 2250);
PAINT SKYBLUE (-8525 2250);
FORCEPROP 1 LAST PART_NUMBER TMP_QCS21002JB34
J 2
(-8525 2275);
DISPLAY 0.489362 (-8525 2275);
PAINT SKYBLUE (-8525 2275);
FORCEPROP 2 LAST BOM_COST MEM
J 2
(-8525 2475);
DISPLAY 0.808511 (-8525 2475);
DISPLAY INVISIBLE (-8525 2475);
FORCEPROP 2 LAST CDS_LIB pure_quanta
J 2
(-8475 2300);
DISPLAY INVISIBLE (-8475 2300);
FORCEPROP 1 LAST PATH I190
J 2
(-8525 2475);
DISPLAY 0.978723 (-8525 2475);
PAINT WHITE (-8525 2475);
DISPLAY INVISIBLE (-8525 2475);
FORCEPROP 2 LAST ROOM MEM_CH_A_CPU0_DIMM1
J 2
(-8525 2525);
DISPLAY 0.808511 (-8525 2525);
PAINT RED (-8525 2525);
DISPLAY INVISIBLE (-8525 2525);
FORCEADD OFFPAGE..2
(-2300 4575);
FORCEPROP 2 LAST $XR0 16 
J 0
(-2111 4575);
DISPLAY 0.638298 (-2111 4575);
PAINT MONO (-2111 4575);
FORCEPROP 2 LAST PATH I192
J 0
(-2100 4625);
DISPLAY 0.680851 (-2100 4625);
DISPLAY INVISIBLE (-2100 4625);
FORCEPROP 1 LAST COMMENT_BODY TRUE
J 0
(-2345 4480);
DISPLAY 0.872340 (-2345 4480);
PAINT GREEN (-2345 4480);
DISPLAY INVISIBLE (-2345 4480);
FORCEPROP 1 LAST OFFPAGE TRUE
J 0
(-1975 4450);
DISPLAY 0.723404 (-1975 4450);
PAINT GREEN (-1975 4450);
DISPLAY INVISIBLE (-1975 4450);
FORCEPROP 2 LAST CDS_LIB mstr_standard
J 0
(-2300 4575);
DISPLAY 0.723404 (-2300 4575);
PAINT MONO (-2300 4575);
DISPLAY INVISIBLE (-2300 4575);
FORCEADD OFFPAGE..2
(-2300 4625);
FORCEPROP 2 LAST $XR0 16 
J 0
(-2111 4625);
DISPLAY 0.638298 (-2111 4625);
PAINT MONO (-2111 4625);
FORCEPROP 2 LAST PATH I193
J 0
(-2100 4675);
DISPLAY 0.680851 (-2100 4675);
DISPLAY INVISIBLE (-2100 4675);
FORCEPROP 1 LAST COMMENT_BODY TRUE
J 0
(-2345 4530);
DISPLAY 0.872340 (-2345 4530);
PAINT GREEN (-2345 4530);
DISPLAY INVISIBLE (-2345 4530);
FORCEPROP 1 LAST OFFPAGE TRUE
J 0
(-1975 4500);
DISPLAY 0.723404 (-1975 4500);
PAINT GREEN (-1975 4500);
DISPLAY INVISIBLE (-1975 4500);
FORCEPROP 2 LAST CDS_LIB mstr_standard
J 0
(-2300 4625);
DISPLAY 0.723404 (-2300 4625);
PAINT MONO (-2300 4625);
DISPLAY INVISIBLE (-2300 4625);
FORCEADD OFFPAGE..2
(-2300 3525);
FORCEPROP 2 LAST $XR0 16 
J 0
(-2111 3525);
DISPLAY 0.638298 (-2111 3525);
PAINT MONO (-2111 3525);
FORCEPROP 2 LAST PATH I194
J 0
(-2100 3575);
DISPLAY 0.680851 (-2100 3575);
DISPLAY INVISIBLE (-2100 3575);
FORCEPROP 1 LAST COMMENT_BODY TRUE
J 0
(-2345 3430);
DISPLAY 0.872340 (-2345 3430);
PAINT GREEN (-2345 3430);
DISPLAY INVISIBLE (-2345 3430);
FORCEPROP 1 LAST OFFPAGE TRUE
J 0
(-1975 3400);
DISPLAY 0.723404 (-1975 3400);
PAINT GREEN (-1975 3400);
DISPLAY INVISIBLE (-1975 3400);
FORCEPROP 2 LAST CDS_LIB mstr_standard
J 0
(-2300 3525);
DISPLAY 0.723404 (-2300 3525);
PAINT MONO (-2300 3525);
DISPLAY INVISIBLE (-2300 3525);
FORCEADD OFFPAGE..2
(-2300 3575);
FORCEPROP 2 LAST $XR0 16 
J 0
(-2111 3575);
DISPLAY 0.638298 (-2111 3575);
PAINT MONO (-2111 3575);
FORCEPROP 2 LAST PATH I195
J 0
(-2100 3625);
DISPLAY 0.680851 (-2100 3625);
DISPLAY INVISIBLE (-2100 3625);
FORCEPROP 1 LAST COMMENT_BODY TRUE
J 0
(-2345 3480);
DISPLAY 0.872340 (-2345 3480);
PAINT GREEN (-2345 3480);
DISPLAY INVISIBLE (-2345 3480);
FORCEPROP 1 LAST OFFPAGE TRUE
J 0
(-1975 3450);
DISPLAY 0.723404 (-1975 3450);
PAINT GREEN (-1975 3450);
DISPLAY INVISIBLE (-1975 3450);
FORCEPROP 2 LAST CDS_LIB mstr_standard
J 0
(-2300 3575);
DISPLAY 0.723404 (-2300 3575);
PAINT MONO (-2300 3575);
DISPLAY INVISIBLE (-2300 3575);
FORCEADD TAP..1
(-2900 4525);
FORCEPROP 3 LASTPIN (-2950 4525) SIG_NAME M_G_CPU0_SA_DQS_DN<9>
J 0
(-2940 4535);
DISPLAY 0.659574 (-2940 4535);
PAINT MONO (-2940 4535);
DISPLAY INVISIBLE (-2940 4535);
FORCEPROP 1 LASTPIN (-2950 4525) BN 9
J 0
(-2962 4533);
DISPLAY 0.489362 (-2962 4533);
PAINT GREEN (-2962 4533);
FORCEPROP 2 LAST CDS_LIB mstr_standard
J 0
(-2900 4525);
DISPLAY 0.723404 (-2900 4525);
PAINT MONO (-2900 4525);
DISPLAY INVISIBLE (-2900 4525);
FORCEPROP 1 LAST BODY_TYPE PLUMBING
J 0
(-2900 4575);
DISPLAY 0.872340 (-2900 4575);
PAINT GREEN (-2900 4575);
DISPLAY INVISIBLE (-2900 4575);
FORCEPROP 1 LAST HDL_TAP TRUE
J 0
(-2575 4400);
DISPLAY 0.872340 (-2575 4400);
DISPLAY INVISIBLE (-2575 4400);
FORCEPROP 1 LAST PATH I196
J 0
(-2902 4525);
DISPLAY 0.872340 (-2902 4525);
PAINT GREEN (-2902 4525);
DISPLAY INVISIBLE (-2902 4525);
FORCEADD TAP..1
(-2900 4425);
FORCEPROP 3 LASTPIN (-2950 4425) SIG_NAME M_G_CPU0_SA_DQS_DN<8>
J 0
(-2940 4435);
DISPLAY 0.659574 (-2940 4435);
PAINT MONO (-2940 4435);
DISPLAY INVISIBLE (-2940 4435);
FORCEPROP 1 LASTPIN (-2950 4425) BN 8
J 0
(-2962 4433);
DISPLAY 0.489362 (-2962 4433);
PAINT GREEN (-2962 4433);
FORCEPROP 2 LAST CDS_LIB mstr_standard
J 0
(-2900 4425);
DISPLAY 0.723404 (-2900 4425);
PAINT MONO (-2900 4425);
DISPLAY INVISIBLE (-2900 4425);
FORCEPROP 1 LAST BODY_TYPE PLUMBING
J 0
(-2900 4475);
DISPLAY 0.872340 (-2900 4475);
PAINT GREEN (-2900 4475);
DISPLAY INVISIBLE (-2900 4475);
FORCEPROP 1 LAST HDL_TAP TRUE
J 0
(-2575 4300);
DISPLAY 0.872340 (-2575 4300);
DISPLAY INVISIBLE (-2575 4300);
FORCEPROP 1 LAST PATH I197
J 0
(-2902 4425);
DISPLAY 0.872340 (-2902 4425);
PAINT GREEN (-2902 4425);
DISPLAY INVISIBLE (-2902 4425);
FORCEADD TAP..1
(-3100 4575);
FORCEPROP 3 LASTPIN (-3150 4575) SIG_NAME M_G_CPU0_SA_DQS_DP<9>
J 0
(-3140 4585);
DISPLAY 0.659574 (-3140 4585);
PAINT MONO (-3140 4585);
DISPLAY INVISIBLE (-3140 4585);
FORCEPROP 1 LASTPIN (-3150 4575) BN 9
J 0
(-3162 4583);
DISPLAY 0.489362 (-3162 4583);
PAINT GREEN (-3162 4583);
FORCEPROP 2 LAST CDS_LIB mstr_standard
J 0
(-3100 4575);
DISPLAY 0.723404 (-3100 4575);
PAINT MONO (-3100 4575);
DISPLAY INVISIBLE (-3100 4575);
FORCEPROP 1 LAST BODY_TYPE PLUMBING
J 0
(-3100 4625);
DISPLAY 0.872340 (-3100 4625);
PAINT GREEN (-3100 4625);
DISPLAY INVISIBLE (-3100 4625);
FORCEPROP 1 LAST HDL_TAP TRUE
J 0
(-2775 4450);
DISPLAY 0.872340 (-2775 4450);
DISPLAY INVISIBLE (-2775 4450);
FORCEPROP 1 LAST PATH I198
J 0
(-3102 4575);
DISPLAY 0.872340 (-3102 4575);
PAINT GREEN (-3102 4575);
DISPLAY INVISIBLE (-3102 4575);
FORCEADD TAP..1
(-3100 4475);
FORCEPROP 3 LASTPIN (-3150 4475) SIG_NAME M_G_CPU0_SA_DQS_DP<8>
J 0
(-3140 4485);
DISPLAY 0.659574 (-3140 4485);
PAINT MONO (-3140 4485);
DISPLAY INVISIBLE (-3140 4485);
FORCEPROP 1 LASTPIN (-3150 4475) BN 8
J 0
(-3162 4483);
DISPLAY 0.489362 (-3162 4483);
PAINT GREEN (-3162 4483);
FORCEPROP 2 LAST CDS_LIB mstr_standard
J 0
(-3100 4475);
DISPLAY 0.723404 (-3100 4475);
PAINT MONO (-3100 4475);
DISPLAY INVISIBLE (-3100 4475);
FORCEPROP 1 LAST BODY_TYPE PLUMBING
J 0
(-3100 4525);
DISPLAY 0.872340 (-3100 4525);
PAINT GREEN (-3100 4525);
DISPLAY INVISIBLE (-3100 4525);
FORCEPROP 1 LAST HDL_TAP TRUE
J 0
(-2775 4350);
DISPLAY 0.872340 (-2775 4350);
DISPLAY INVISIBLE (-2775 4350);
FORCEPROP 1 LAST PATH I199
J 0
(-3102 4475);
DISPLAY 0.872340 (-3102 4475);
PAINT GREEN (-3102 4475);
DISPLAY INVISIBLE (-3102 4475);
FORCEADD OFFPAGE..5
(-7925 2000);
FORCEPROP 2 LAST $XR0 16 
J 0
(-8149 2000);
DISPLAY 0.638298 (-8149 2000);
PAINT MONO (-8149 2000);
FORCEPROP 2 LAST PATH I2
J 0
(-8125 2050);
DISPLAY 1.021277 (-8125 2050);
DISPLAY INVISIBLE (-8125 2050);
FORCEPROP 1 LAST COMMENT_BODY TRUE
J 0
(-7825 1925);
DISPLAY 0.872340 (-7825 1925);
PAINT GREEN (-7825 1925);
DISPLAY INVISIBLE (-7825 1925);
FORCEPROP 1 LAST OFFPAGE TRUE
J 0
(-7600 1875);
DISPLAY 0.872340 (-7600 1875);
PAINT GREEN (-7600 1875);
DISPLAY INVISIBLE (-7600 1875);
FORCEPROP 2 LAST CDS_LIB mstr_standard
J 0
(-7925 2000);
DISPLAY 0.808511 (-7925 2000);
DISPLAY INVISIBLE (-7925 2000);
FORCEADD OFFPAGE..1
(-7925 5050);
FORCEPROP 2 LAST $XR0 16 
J 0
(-8176 5050);
DISPLAY 0.638298 (-8176 5050);
PAINT MONO (-8176 5050);
FORCEPROP 2 LAST PATH I20
J 0
(-8175 5100);
DISPLAY 1.021277 (-8175 5100);
DISPLAY INVISIBLE (-8175 5100);
FORCEPROP 1 LAST COMMENT_BODY TRUE
J 0
(-7800 4950);
DISPLAY 0.872340 (-7800 4950);
PAINT GREEN (-7800 4950);
DISPLAY INVISIBLE (-7800 4950);
FORCEPROP 1 LAST OFFPAGE TRUE
J 0
(-7600 4925);
DISPLAY 0.872340 (-7600 4925);
PAINT GREEN (-7600 4925);
DISPLAY INVISIBLE (-7600 4925);
FORCEPROP 2 LAST CDS_LIB mstr_standard
J 0
(-7925 5050);
DISPLAY 0.723404 (-7925 5050);
PAINT MONO (-7925 5050);
DISPLAY INVISIBLE (-7925 5050);
FORCEADD TAP..1
(-3100 4375);
FORCEPROP 3 LASTPIN (-3150 4375) SIG_NAME M_G_CPU0_SA_DQS_DP<7>
J 0
(-3140 4385);
DISPLAY 0.659574 (-3140 4385);
PAINT MONO (-3140 4385);
DISPLAY INVISIBLE (-3140 4385);
FORCEPROP 1 LASTPIN (-3150 4375) BN 7
J 0
(-3162 4383);
DISPLAY 0.489362 (-3162 4383);
PAINT GREEN (-3162 4383);
FORCEPROP 2 LAST CDS_LIB mstr_standard
J 0
(-3100 4375);
DISPLAY 0.723404 (-3100 4375);
PAINT MONO (-3100 4375);
DISPLAY INVISIBLE (-3100 4375);
FORCEPROP 1 LAST BODY_TYPE PLUMBING
J 0
(-3100 4425);
DISPLAY 0.872340 (-3100 4425);
PAINT GREEN (-3100 4425);
DISPLAY INVISIBLE (-3100 4425);
FORCEPROP 1 LAST HDL_TAP TRUE
J 0
(-2775 4250);
DISPLAY 0.872340 (-2775 4250);
DISPLAY INVISIBLE (-2775 4250);
FORCEPROP 1 LAST PATH I200
J 0
(-3102 4375);
DISPLAY 0.872340 (-3102 4375);
PAINT GREEN (-3102 4375);
DISPLAY INVISIBLE (-3102 4375);
FORCEADD TAP..1
(-2900 4325);
FORCEPROP 3 LASTPIN (-2950 4325) SIG_NAME M_G_CPU0_SA_DQS_DN<7>
J 0
(-2940 4335);
DISPLAY 0.659574 (-2940 4335);
PAINT MONO (-2940 4335);
DISPLAY INVISIBLE (-2940 4335);
FORCEPROP 1 LASTPIN (-2950 4325) BN 7
J 0
(-2962 4333);
DISPLAY 0.489362 (-2962 4333);
PAINT GREEN (-2962 4333);
FORCEPROP 2 LAST CDS_LIB mstr_standard
J 0
(-2900 4325);
DISPLAY 0.723404 (-2900 4325);
PAINT MONO (-2900 4325);
DISPLAY INVISIBLE (-2900 4325);
FORCEPROP 1 LAST BODY_TYPE PLUMBING
J 0
(-2900 4375);
DISPLAY 0.872340 (-2900 4375);
PAINT GREEN (-2900 4375);
DISPLAY INVISIBLE (-2900 4375);
FORCEPROP 1 LAST HDL_TAP TRUE
J 0
(-2575 4200);
DISPLAY 0.872340 (-2575 4200);
DISPLAY INVISIBLE (-2575 4200);
FORCEPROP 1 LAST PATH I201
J 0
(-2902 4325);
DISPLAY 0.872340 (-2902 4325);
PAINT GREEN (-2902 4325);
DISPLAY INVISIBLE (-2902 4325);
FORCEADD TAP..1
(-2900 4125);
FORCEPROP 3 LASTPIN (-2950 4125) SIG_NAME M_G_CPU0_SA_DQS_DN<5>
J 0
(-2940 4135);
DISPLAY 0.659574 (-2940 4135);
PAINT MONO (-2940 4135);
DISPLAY INVISIBLE (-2940 4135);
FORCEPROP 1 LASTPIN (-2950 4125) BN 5
J 0
(-2962 4133);
DISPLAY 0.489362 (-2962 4133);
PAINT GREEN (-2962 4133);
FORCEPROP 2 LAST CDS_LIB mstr_standard
J 0
(-2900 4125);
DISPLAY 0.723404 (-2900 4125);
PAINT MONO (-2900 4125);
DISPLAY INVISIBLE (-2900 4125);
FORCEPROP 1 LAST BODY_TYPE PLUMBING
J 0
(-2900 4175);
DISPLAY 0.872340 (-2900 4175);
PAINT GREEN (-2900 4175);
DISPLAY INVISIBLE (-2900 4175);
FORCEPROP 1 LAST HDL_TAP TRUE
J 0
(-2575 4000);
DISPLAY 0.872340 (-2575 4000);
DISPLAY INVISIBLE (-2575 4000);
FORCEPROP 1 LAST PATH I202
J 0
(-2902 4125);
DISPLAY 0.872340 (-2902 4125);
PAINT GREEN (-2902 4125);
DISPLAY INVISIBLE (-2902 4125);
FORCEADD TAP..1
(-2900 4225);
FORCEPROP 3 LASTPIN (-2950 4225) SIG_NAME M_G_CPU0_SA_DQS_DN<6>
J 0
(-2940 4235);
DISPLAY 0.659574 (-2940 4235);
PAINT MONO (-2940 4235);
DISPLAY INVISIBLE (-2940 4235);
FORCEPROP 1 LASTPIN (-2950 4225) BN 6
J 0
(-2962 4233);
DISPLAY 0.489362 (-2962 4233);
PAINT GREEN (-2962 4233);
FORCEPROP 2 LAST CDS_LIB mstr_standard
J 0
(-2900 4225);
DISPLAY 0.723404 (-2900 4225);
PAINT MONO (-2900 4225);
DISPLAY INVISIBLE (-2900 4225);
FORCEPROP 1 LAST BODY_TYPE PLUMBING
J 0
(-2900 4275);
DISPLAY 0.872340 (-2900 4275);
PAINT GREEN (-2900 4275);
DISPLAY INVISIBLE (-2900 4275);
FORCEPROP 1 LAST HDL_TAP TRUE
J 0
(-2575 4100);
DISPLAY 0.872340 (-2575 4100);
DISPLAY INVISIBLE (-2575 4100);
FORCEPROP 1 LAST PATH I203
J 0
(-2902 4225);
DISPLAY 0.872340 (-2902 4225);
PAINT GREEN (-2902 4225);
DISPLAY INVISIBLE (-2902 4225);
FORCEADD TAP..1
(-2900 4025);
FORCEPROP 3 LASTPIN (-2950 4025) SIG_NAME M_G_CPU0_SA_DQS_DN<4>
J 0
(-2940 4035);
DISPLAY 0.659574 (-2940 4035);
PAINT MONO (-2940 4035);
DISPLAY INVISIBLE (-2940 4035);
FORCEPROP 1 LASTPIN (-2950 4025) BN 4
J 0
(-2962 4033);
DISPLAY 0.489362 (-2962 4033);
PAINT GREEN (-2962 4033);
FORCEPROP 2 LAST CDS_LIB mstr_standard
J 0
(-2900 4025);
DISPLAY 0.723404 (-2900 4025);
PAINT MONO (-2900 4025);
DISPLAY INVISIBLE (-2900 4025);
FORCEPROP 1 LAST BODY_TYPE PLUMBING
J 0
(-2900 4075);
DISPLAY 0.872340 (-2900 4075);
PAINT GREEN (-2900 4075);
DISPLAY INVISIBLE (-2900 4075);
FORCEPROP 1 LAST HDL_TAP TRUE
J 0
(-2575 3900);
DISPLAY 0.872340 (-2575 3900);
DISPLAY INVISIBLE (-2575 3900);
FORCEPROP 1 LAST PATH I204
J 0
(-2902 4025);
DISPLAY 0.872340 (-2902 4025);
PAINT GREEN (-2902 4025);
DISPLAY INVISIBLE (-2902 4025);
FORCEADD TAP..1
(-2900 3925);
FORCEPROP 3 LASTPIN (-2950 3925) SIG_NAME M_G_CPU0_SA_DQS_DN<3>
J 0
(-2940 3935);
DISPLAY 0.659574 (-2940 3935);
PAINT MONO (-2940 3935);
DISPLAY INVISIBLE (-2940 3935);
FORCEPROP 1 LASTPIN (-2950 3925) BN 3
J 0
(-2962 3933);
DISPLAY 0.489362 (-2962 3933);
PAINT GREEN (-2962 3933);
FORCEPROP 2 LAST CDS_LIB mstr_standard
J 0
(-2900 3925);
DISPLAY 0.723404 (-2900 3925);
PAINT MONO (-2900 3925);
DISPLAY INVISIBLE (-2900 3925);
FORCEPROP 1 LAST BODY_TYPE PLUMBING
J 0
(-2900 3975);
DISPLAY 0.872340 (-2900 3975);
PAINT GREEN (-2900 3975);
DISPLAY INVISIBLE (-2900 3975);
FORCEPROP 1 LAST HDL_TAP TRUE
J 0
(-2575 3800);
DISPLAY 0.872340 (-2575 3800);
DISPLAY INVISIBLE (-2575 3800);
FORCEPROP 1 LAST PATH I205
J 0
(-2902 3925);
DISPLAY 0.872340 (-2902 3925);
PAINT GREEN (-2902 3925);
DISPLAY INVISIBLE (-2902 3925);
FORCEADD TAP..1
(-3100 4175);
FORCEPROP 3 LASTPIN (-3150 4175) SIG_NAME M_G_CPU0_SA_DQS_DP<5>
J 0
(-3140 4185);
DISPLAY 0.659574 (-3140 4185);
PAINT MONO (-3140 4185);
DISPLAY INVISIBLE (-3140 4185);
FORCEPROP 1 LASTPIN (-3150 4175) BN 5
J 0
(-3162 4183);
DISPLAY 0.489362 (-3162 4183);
PAINT GREEN (-3162 4183);
FORCEPROP 2 LAST CDS_LIB mstr_standard
J 0
(-3100 4175);
DISPLAY 0.723404 (-3100 4175);
PAINT MONO (-3100 4175);
DISPLAY INVISIBLE (-3100 4175);
FORCEPROP 1 LAST BODY_TYPE PLUMBING
J 0
(-3100 4225);
DISPLAY 0.872340 (-3100 4225);
PAINT GREEN (-3100 4225);
DISPLAY INVISIBLE (-3100 4225);
FORCEPROP 1 LAST HDL_TAP TRUE
J 0
(-2775 4050);
DISPLAY 0.872340 (-2775 4050);
DISPLAY INVISIBLE (-2775 4050);
FORCEPROP 1 LAST PATH I206
J 0
(-3102 4175);
DISPLAY 0.872340 (-3102 4175);
PAINT GREEN (-3102 4175);
DISPLAY INVISIBLE (-3102 4175);
FORCEADD TAP..1
(-3100 4275);
FORCEPROP 3 LASTPIN (-3150 4275) SIG_NAME M_G_CPU0_SA_DQS_DP<6>
J 0
(-3140 4285);
DISPLAY 0.659574 (-3140 4285);
PAINT MONO (-3140 4285);
DISPLAY INVISIBLE (-3140 4285);
FORCEPROP 1 LASTPIN (-3150 4275) BN 6
J 0
(-3162 4283);
DISPLAY 0.489362 (-3162 4283);
PAINT GREEN (-3162 4283);
FORCEPROP 2 LAST CDS_LIB mstr_standard
J 0
(-3100 4275);
DISPLAY 0.723404 (-3100 4275);
PAINT MONO (-3100 4275);
DISPLAY INVISIBLE (-3100 4275);
FORCEPROP 1 LAST BODY_TYPE PLUMBING
J 0
(-3100 4325);
DISPLAY 0.872340 (-3100 4325);
PAINT GREEN (-3100 4325);
DISPLAY INVISIBLE (-3100 4325);
FORCEPROP 1 LAST HDL_TAP TRUE
J 0
(-2775 4150);
DISPLAY 0.872340 (-2775 4150);
DISPLAY INVISIBLE (-2775 4150);
FORCEPROP 1 LAST PATH I207
J 0
(-3102 4275);
DISPLAY 0.872340 (-3102 4275);
PAINT GREEN (-3102 4275);
DISPLAY INVISIBLE (-3102 4275);
FORCEADD TAP..1
(-3100 4075);
FORCEPROP 3 LASTPIN (-3150 4075) SIG_NAME M_G_CPU0_SA_DQS_DP<4>
J 0
(-3140 4085);
DISPLAY 0.659574 (-3140 4085);
PAINT MONO (-3140 4085);
DISPLAY INVISIBLE (-3140 4085);
FORCEPROP 1 LASTPIN (-3150 4075) BN 4
J 0
(-3162 4083);
DISPLAY 0.489362 (-3162 4083);
PAINT GREEN (-3162 4083);
FORCEPROP 2 LAST CDS_LIB mstr_standard
J 0
(-3100 4075);
DISPLAY 0.723404 (-3100 4075);
PAINT MONO (-3100 4075);
DISPLAY INVISIBLE (-3100 4075);
FORCEPROP 1 LAST BODY_TYPE PLUMBING
J 0
(-3100 4125);
DISPLAY 0.872340 (-3100 4125);
PAINT GREEN (-3100 4125);
DISPLAY INVISIBLE (-3100 4125);
FORCEPROP 1 LAST HDL_TAP TRUE
J 0
(-2775 3950);
DISPLAY 0.872340 (-2775 3950);
DISPLAY INVISIBLE (-2775 3950);
FORCEPROP 1 LAST PATH I208
J 0
(-3102 4075);
DISPLAY 0.872340 (-3102 4075);
PAINT GREEN (-3102 4075);
DISPLAY INVISIBLE (-3102 4075);
FORCEADD TAP..1
(-3100 3875);
FORCEPROP 3 LASTPIN (-3150 3875) SIG_NAME M_G_CPU0_SA_DQS_DP<2>
J 0
(-3140 3885);
DISPLAY 0.659574 (-3140 3885);
PAINT MONO (-3140 3885);
DISPLAY INVISIBLE (-3140 3885);
FORCEPROP 1 LASTPIN (-3150 3875) BN 2
J 0
(-3162 3883);
DISPLAY 0.489362 (-3162 3883);
PAINT GREEN (-3162 3883);
FORCEPROP 2 LAST CDS_LIB mstr_standard
J 0
(-3100 3875);
DISPLAY 0.723404 (-3100 3875);
PAINT MONO (-3100 3875);
DISPLAY INVISIBLE (-3100 3875);
FORCEPROP 1 LAST BODY_TYPE PLUMBING
J 0
(-3100 3925);
DISPLAY 0.872340 (-3100 3925);
PAINT GREEN (-3100 3925);
DISPLAY INVISIBLE (-3100 3925);
FORCEPROP 1 LAST HDL_TAP TRUE
J 0
(-2775 3750);
DISPLAY 0.872340 (-2775 3750);
DISPLAY INVISIBLE (-2775 3750);
FORCEPROP 1 LAST PATH I209
J 0
(-3102 3875);
DISPLAY 0.872340 (-3102 3875);
PAINT GREEN (-3102 3875);
DISPLAY INVISIBLE (-3102 3875);
FORCEADD OFFPAGE..1
(-7925 5450);
FORCEPROP 2 LAST $XR0 16 
J 0
(-8176 5450);
DISPLAY 0.638298 (-8176 5450);
PAINT MONO (-8176 5450);
FORCEPROP 2 LAST PATH I21
J 0
(-8175 5500);
DISPLAY 1.021277 (-8175 5500);
DISPLAY INVISIBLE (-8175 5500);
FORCEPROP 1 LAST COMMENT_BODY TRUE
J 0
(-7800 5350);
DISPLAY 0.872340 (-7800 5350);
PAINT GREEN (-7800 5350);
DISPLAY INVISIBLE (-7800 5350);
FORCEPROP 1 LAST OFFPAGE TRUE
J 0
(-7600 5325);
DISPLAY 0.872340 (-7600 5325);
PAINT GREEN (-7600 5325);
DISPLAY INVISIBLE (-7600 5325);
FORCEPROP 2 LAST CDS_LIB mstr_standard
J 0
(-7925 5450);
DISPLAY 0.723404 (-7925 5450);
PAINT MONO (-7925 5450);
DISPLAY INVISIBLE (-7925 5450);
FORCEADD TAP..1
(-3100 3975);
FORCEPROP 3 LASTPIN (-3150 3975) SIG_NAME M_G_CPU0_SA_DQS_DP<3>
J 0
(-3140 3985);
DISPLAY 0.659574 (-3140 3985);
PAINT MONO (-3140 3985);
DISPLAY INVISIBLE (-3140 3985);
FORCEPROP 1 LASTPIN (-3150 3975) BN 3
J 0
(-3162 3983);
DISPLAY 0.489362 (-3162 3983);
PAINT GREEN (-3162 3983);
FORCEPROP 2 LAST CDS_LIB mstr_standard
J 0
(-3100 3975);
DISPLAY 0.723404 (-3100 3975);
PAINT MONO (-3100 3975);
DISPLAY INVISIBLE (-3100 3975);
FORCEPROP 1 LAST BODY_TYPE PLUMBING
J 0
(-3100 4025);
DISPLAY 0.872340 (-3100 4025);
PAINT GREEN (-3100 4025);
DISPLAY INVISIBLE (-3100 4025);
FORCEPROP 1 LAST HDL_TAP TRUE
J 0
(-2775 3850);
DISPLAY 0.872340 (-2775 3850);
DISPLAY INVISIBLE (-2775 3850);
FORCEPROP 1 LAST PATH I210
J 0
(-3102 3975);
DISPLAY 0.872340 (-3102 3975);
PAINT GREEN (-3102 3975);
DISPLAY INVISIBLE (-3102 3975);
FORCEADD TAP..1
(-2900 3825);
FORCEPROP 3 LASTPIN (-2950 3825) SIG_NAME M_G_CPU0_SA_DQS_DN<2>
J 0
(-2940 3835);
DISPLAY 0.659574 (-2940 3835);
PAINT MONO (-2940 3835);
DISPLAY INVISIBLE (-2940 3835);
FORCEPROP 1 LASTPIN (-2950 3825) BN 2
J 0
(-2962 3833);
DISPLAY 0.489362 (-2962 3833);
PAINT GREEN (-2962 3833);
FORCEPROP 2 LAST CDS_LIB mstr_standard
J 0
(-2900 3825);
DISPLAY 0.723404 (-2900 3825);
PAINT MONO (-2900 3825);
DISPLAY INVISIBLE (-2900 3825);
FORCEPROP 1 LAST BODY_TYPE PLUMBING
J 0
(-2900 3875);
DISPLAY 0.872340 (-2900 3875);
PAINT GREEN (-2900 3875);
DISPLAY INVISIBLE (-2900 3875);
FORCEPROP 1 LAST HDL_TAP TRUE
J 0
(-2575 3700);
DISPLAY 0.872340 (-2575 3700);
DISPLAY INVISIBLE (-2575 3700);
FORCEPROP 1 LAST PATH I211
J 0
(-2902 3825);
DISPLAY 0.872340 (-2902 3825);
PAINT GREEN (-2902 3825);
DISPLAY INVISIBLE (-2902 3825);
FORCEADD TAP..1
(-2900 3725);
FORCEPROP 3 LASTPIN (-2950 3725) SIG_NAME M_G_CPU0_SA_DQS_DN<1>
J 0
(-2940 3735);
DISPLAY 0.659574 (-2940 3735);
PAINT MONO (-2940 3735);
DISPLAY INVISIBLE (-2940 3735);
FORCEPROP 1 LASTPIN (-2950 3725) BN 1
J 0
(-2962 3733);
DISPLAY 0.489362 (-2962 3733);
PAINT GREEN (-2962 3733);
FORCEPROP 2 LAST CDS_LIB mstr_standard
J 0
(-2900 3725);
DISPLAY 0.723404 (-2900 3725);
PAINT MONO (-2900 3725);
DISPLAY INVISIBLE (-2900 3725);
FORCEPROP 1 LAST BODY_TYPE PLUMBING
J 0
(-2900 3775);
DISPLAY 0.872340 (-2900 3775);
PAINT GREEN (-2900 3775);
DISPLAY INVISIBLE (-2900 3775);
FORCEPROP 1 LAST HDL_TAP TRUE
J 0
(-2575 3600);
DISPLAY 0.872340 (-2575 3600);
DISPLAY INVISIBLE (-2575 3600);
FORCEPROP 1 LAST PATH I212
J 0
(-2902 3725);
DISPLAY 0.872340 (-2902 3725);
PAINT GREEN (-2902 3725);
DISPLAY INVISIBLE (-2902 3725);
FORCEADD TAP..1
(-2900 3625);
FORCEPROP 3 LASTPIN (-2950 3625) SIG_NAME M_G_CPU0_SA_DQS_DN<0>
J 0
(-2940 3635);
DISPLAY 0.659574 (-2940 3635);
PAINT MONO (-2940 3635);
DISPLAY INVISIBLE (-2940 3635);
FORCEPROP 1 LASTPIN (-2950 3625) BN 0
J 0
(-2962 3633);
DISPLAY 0.489362 (-2962 3633);
PAINT GREEN (-2962 3633);
FORCEPROP 2 LAST CDS_LIB mstr_standard
J 0
(-2900 3625);
DISPLAY 0.723404 (-2900 3625);
PAINT MONO (-2900 3625);
DISPLAY INVISIBLE (-2900 3625);
FORCEPROP 1 LAST BODY_TYPE PLUMBING
J 0
(-2900 3675);
DISPLAY 0.872340 (-2900 3675);
PAINT GREEN (-2900 3675);
DISPLAY INVISIBLE (-2900 3675);
FORCEPROP 1 LAST HDL_TAP TRUE
J 0
(-2575 3500);
DISPLAY 0.872340 (-2575 3500);
DISPLAY INVISIBLE (-2575 3500);
FORCEPROP 1 LAST PATH I213
J 0
(-2902 3625);
DISPLAY 0.872340 (-2902 3625);
PAINT GREEN (-2902 3625);
DISPLAY INVISIBLE (-2902 3625);
FORCEADD TAP..1
(-2900 3475);
FORCEPROP 3 LASTPIN (-2950 3475) SIG_NAME M_G_CPU0_SB_DQS_DN<9>
J 0
(-2940 3485);
DISPLAY 0.659574 (-2940 3485);
PAINT MONO (-2940 3485);
DISPLAY INVISIBLE (-2940 3485);
FORCEPROP 1 LASTPIN (-2950 3475) BN 9
J 0
(-2962 3483);
DISPLAY 0.489362 (-2962 3483);
PAINT GREEN (-2962 3483);
FORCEPROP 2 LAST CDS_LIB mstr_standard
J 0
(-2900 3475);
DISPLAY 0.723404 (-2900 3475);
PAINT MONO (-2900 3475);
DISPLAY INVISIBLE (-2900 3475);
FORCEPROP 1 LAST BODY_TYPE PLUMBING
J 0
(-2900 3525);
DISPLAY 0.872340 (-2900 3525);
PAINT GREEN (-2900 3525);
DISPLAY INVISIBLE (-2900 3525);
FORCEPROP 1 LAST HDL_TAP TRUE
J 0
(-2575 3350);
DISPLAY 0.872340 (-2575 3350);
DISPLAY INVISIBLE (-2575 3350);
FORCEPROP 1 LAST PATH I214
J 0
(-2902 3475);
DISPLAY 0.872340 (-2902 3475);
PAINT GREEN (-2902 3475);
DISPLAY INVISIBLE (-2902 3475);
FORCEADD TAP..1
(-2900 3375);
FORCEPROP 3 LASTPIN (-2950 3375) SIG_NAME M_G_CPU0_SB_DQS_DN<8>
J 0
(-2940 3385);
DISPLAY 0.659574 (-2940 3385);
PAINT MONO (-2940 3385);
DISPLAY INVISIBLE (-2940 3385);
FORCEPROP 1 LASTPIN (-2950 3375) BN 8
J 0
(-2962 3383);
DISPLAY 0.489362 (-2962 3383);
PAINT GREEN (-2962 3383);
FORCEPROP 2 LAST CDS_LIB mstr_standard
J 0
(-2900 3375);
DISPLAY 0.723404 (-2900 3375);
PAINT MONO (-2900 3375);
DISPLAY INVISIBLE (-2900 3375);
FORCEPROP 1 LAST BODY_TYPE PLUMBING
J 0
(-2900 3425);
DISPLAY 0.872340 (-2900 3425);
PAINT GREEN (-2900 3425);
DISPLAY INVISIBLE (-2900 3425);
FORCEPROP 1 LAST HDL_TAP TRUE
J 0
(-2575 3250);
DISPLAY 0.872340 (-2575 3250);
DISPLAY INVISIBLE (-2575 3250);
FORCEPROP 1 LAST PATH I215
J 0
(-2902 3375);
DISPLAY 0.872340 (-2902 3375);
PAINT GREEN (-2902 3375);
DISPLAY INVISIBLE (-2902 3375);
FORCEADD TAP..1
(-3100 3675);
FORCEPROP 3 LASTPIN (-3150 3675) SIG_NAME M_G_CPU0_SA_DQS_DP<0>
J 0
(-3140 3685);
DISPLAY 0.659574 (-3140 3685);
PAINT MONO (-3140 3685);
DISPLAY INVISIBLE (-3140 3685);
FORCEPROP 1 LASTPIN (-3150 3675) BN 0
J 0
(-3162 3683);
DISPLAY 0.489362 (-3162 3683);
PAINT GREEN (-3162 3683);
FORCEPROP 2 LAST CDS_LIB mstr_standard
J 0
(-3100 3675);
DISPLAY 0.723404 (-3100 3675);
PAINT MONO (-3100 3675);
DISPLAY INVISIBLE (-3100 3675);
FORCEPROP 1 LAST BODY_TYPE PLUMBING
J 0
(-3100 3725);
DISPLAY 0.872340 (-3100 3725);
PAINT GREEN (-3100 3725);
DISPLAY INVISIBLE (-3100 3725);
FORCEPROP 1 LAST HDL_TAP TRUE
J 0
(-2775 3550);
DISPLAY 0.872340 (-2775 3550);
DISPLAY INVISIBLE (-2775 3550);
FORCEPROP 1 LAST PATH I216
J 0
(-3102 3675);
DISPLAY 0.872340 (-3102 3675);
PAINT GREEN (-3102 3675);
DISPLAY INVISIBLE (-3102 3675);
FORCEADD TAP..1
(-3100 3775);
FORCEPROP 3 LASTPIN (-3150 3775) SIG_NAME M_G_CPU0_SA_DQS_DP<1>
J 0
(-3140 3785);
DISPLAY 0.659574 (-3140 3785);
PAINT MONO (-3140 3785);
DISPLAY INVISIBLE (-3140 3785);
FORCEPROP 1 LASTPIN (-3150 3775) BN 1
J 0
(-3162 3783);
DISPLAY 0.489362 (-3162 3783);
PAINT GREEN (-3162 3783);
FORCEPROP 2 LAST CDS_LIB mstr_standard
J 0
(-3100 3775);
DISPLAY 0.723404 (-3100 3775);
PAINT MONO (-3100 3775);
DISPLAY INVISIBLE (-3100 3775);
FORCEPROP 1 LAST BODY_TYPE PLUMBING
J 0
(-3100 3825);
DISPLAY 0.872340 (-3100 3825);
PAINT GREEN (-3100 3825);
DISPLAY INVISIBLE (-3100 3825);
FORCEPROP 1 LAST HDL_TAP TRUE
J 0
(-2775 3650);
DISPLAY 0.872340 (-2775 3650);
DISPLAY INVISIBLE (-2775 3650);
FORCEPROP 1 LAST PATH I217
J 0
(-3102 3775);
DISPLAY 0.872340 (-3102 3775);
PAINT GREEN (-3102 3775);
DISPLAY INVISIBLE (-3102 3775);
FORCEADD TAP..1
(-3100 3425);
FORCEPROP 3 LASTPIN (-3150 3425) SIG_NAME M_G_CPU0_SB_DQS_DP<8>
J 0
(-3140 3435);
DISPLAY 0.659574 (-3140 3435);
PAINT MONO (-3140 3435);
DISPLAY INVISIBLE (-3140 3435);
FORCEPROP 1 LASTPIN (-3150 3425) BN 8
J 0
(-3162 3433);
DISPLAY 0.489362 (-3162 3433);
PAINT GREEN (-3162 3433);
FORCEPROP 2 LAST CDS_LIB mstr_standard
J 0
(-3100 3425);
DISPLAY 0.723404 (-3100 3425);
PAINT MONO (-3100 3425);
DISPLAY INVISIBLE (-3100 3425);
FORCEPROP 1 LAST BODY_TYPE PLUMBING
J 0
(-3100 3475);
DISPLAY 0.872340 (-3100 3475);
PAINT GREEN (-3100 3475);
DISPLAY INVISIBLE (-3100 3475);
FORCEPROP 1 LAST HDL_TAP TRUE
J 0
(-2775 3300);
DISPLAY 0.872340 (-2775 3300);
DISPLAY INVISIBLE (-2775 3300);
FORCEPROP 1 LAST PATH I218
J 0
(-3102 3425);
DISPLAY 0.872340 (-3102 3425);
PAINT GREEN (-3102 3425);
DISPLAY INVISIBLE (-3102 3425);
FORCEADD TAP..1
(-3100 3525);
FORCEPROP 3 LASTPIN (-3150 3525) SIG_NAME M_G_CPU0_SB_DQS_DP<9>
J 0
(-3140 3535);
DISPLAY 0.659574 (-3140 3535);
PAINT MONO (-3140 3535);
DISPLAY INVISIBLE (-3140 3535);
FORCEPROP 1 LASTPIN (-3150 3525) BN 9
J 0
(-3162 3533);
DISPLAY 0.489362 (-3162 3533);
PAINT GREEN (-3162 3533);
FORCEPROP 2 LAST CDS_LIB mstr_standard
J 0
(-3100 3525);
DISPLAY 0.723404 (-3100 3525);
PAINT MONO (-3100 3525);
DISPLAY INVISIBLE (-3100 3525);
FORCEPROP 1 LAST BODY_TYPE PLUMBING
J 0
(-3100 3575);
DISPLAY 0.872340 (-3100 3575);
PAINT GREEN (-3100 3575);
DISPLAY INVISIBLE (-3100 3575);
FORCEPROP 1 LAST HDL_TAP TRUE
J 0
(-2775 3400);
DISPLAY 0.872340 (-2775 3400);
DISPLAY INVISIBLE (-2775 3400);
FORCEPROP 1 LAST PATH I219
J 0
(-3102 3525);
DISPLAY 0.872340 (-3102 3525);
PAINT GREEN (-3102 3525);
DISPLAY INVISIBLE (-3102 3525);
FORCEADD SCONN288_DDR506112002KQ..1
(-6475 3650);
FORCEPROP 1 LAST LOCATION J16
J 0
(-6925 5725);
DISPLAY 0.468085 (-6925 5725);
PAINT SKYBLUE (-6925 5725);
FORCEPROP 0 LAST $SEC 1
J 0
(-6925 5875);
DISPLAY 0.680851 (-6925 5875);
PAINT MONO (-6925 5875);
DISPLAY INVISIBLE (-6925 5875);
FORCEPROP 0 LAST CDS_SEC 1
J 0
(-6925 5875);
DISPLAY 0.680851 (-6925 5875);
DISPLAY INVISIBLE (-6925 5875);
FORCEPROP 0 LASTPIN (-7075 3050) $PN 62
J 2
(-7085 3060);
DISPLAY 0.680851 (-7085 3060);
PAINT MONO (-7085 3060);
FORCEPROP 0 LASTPIN (-7075 5100) $PN 66
J 2
(-7085 5110);
DISPLAY 0.680851 (-7085 5110);
PAINT MONO (-7085 5110);
FORCEPROP 0 LASTPIN (-7075 4700) $PN 76
J 2
(-7085 4710);
DISPLAY 0.680851 (-7085 4710);
PAINT MONO (-7085 4710);
FORCEPROP 0 LASTPIN (-7075 5150) $PN 211
J 2
(-7085 5160);
DISPLAY 0.680851 (-7085 5160);
PAINT MONO (-7085 5160);
FORCEPROP 0 LASTPIN (-7075 4750) $PN 221
J 2
(-7085 4760);
DISPLAY 0.680851 (-7085 4760);
PAINT MONO (-7085 4760);
FORCEPROP 0 LASTPIN (-7075 5200) $PN 68
J 2
(-7085 5210);
DISPLAY 0.680851 (-7085 5210);
PAINT MONO (-7085 5210);
FORCEPROP 0 LASTPIN (-7075 4800) $PN 78
J 2
(-7085 4810);
DISPLAY 0.680851 (-7085 4810);
PAINT MONO (-7085 4810);
FORCEPROP 0 LASTPIN (-7075 5250) $PN 213
J 2
(-7085 5260);
DISPLAY 0.680851 (-7085 5260);
PAINT MONO (-7085 5260);
FORCEPROP 0 LASTPIN (-7075 4850) $PN 223
J 2
(-7085 4860);
DISPLAY 0.680851 (-7085 4860);
PAINT MONO (-7085 4860);
FORCEPROP 0 LASTPIN (-7075 5300) $PN 70
J 2
(-7085 5310);
DISPLAY 0.680851 (-7085 5310);
PAINT MONO (-7085 5310);
FORCEPROP 0 LASTPIN (-7075 4900) $PN 80
J 2
(-7085 4910);
DISPLAY 0.680851 (-7085 4910);
PAINT MONO (-7085 4910);
FORCEPROP 0 LASTPIN (-7075 5350) $PN 215
J 2
(-7085 5360);
DISPLAY 0.680851 (-7085 5360);
PAINT MONO (-7085 5360);
FORCEPROP 0 LASTPIN (-7075 4950) $PN 225
J 2
(-7085 4960);
DISPLAY 0.680851 (-7085 4960);
PAINT MONO (-7085 4960);
FORCEPROP 0 LASTPIN (-7075 5400) $PN 72
J 2
(-7085 5410);
DISPLAY 0.680851 (-7085 5410);
PAINT MONO (-7085 5410);
FORCEPROP 0 LASTPIN (-7075 5000) $PN 82
J 2
(-7085 5010);
DISPLAY 0.680851 (-7085 5010);
PAINT MONO (-7085 5010);
FORCEPROP 0 LASTPIN (-7075 3650) $PN 51
J 2
(-7085 3660);
DISPLAY 0.680851 (-7085 3660);
PAINT MONO (-7085 3660);
FORCEPROP 0 LASTPIN (-7075 3200) $PN 96
J 2
(-7085 3210);
DISPLAY 0.680851 (-7085 3210);
PAINT MONO (-7085 3210);
FORCEPROP 0 LASTPIN (-7075 3700) $PN 53
J 2
(-7085 3710);
DISPLAY 0.680851 (-7085 3710);
PAINT MONO (-7085 3710);
FORCEPROP 0 LASTPIN (-7075 3250) $PN 98
J 2
(-7085 3260);
DISPLAY 0.680851 (-7085 3260);
PAINT MONO (-7085 3260);
FORCEPROP 0 LASTPIN (-7075 3750) $PN 196
J 2
(-7085 3760);
DISPLAY 0.680851 (-7085 3760);
PAINT MONO (-7085 3760);
FORCEPROP 0 LASTPIN (-7075 3300) $PN 241
J 2
(-7085 3310);
DISPLAY 0.680851 (-7085 3310);
PAINT MONO (-7085 3310);
FORCEPROP 0 LASTPIN (-7075 3800) $PN 198
J 2
(-7085 3810);
DISPLAY 0.680851 (-7085 3810);
PAINT MONO (-7085 3810);
FORCEPROP 0 LASTPIN (-7075 3350) $PN 243
J 2
(-7085 3360);
DISPLAY 0.680851 (-7085 3360);
PAINT MONO (-7085 3360);
FORCEPROP 0 LASTPIN (-7075 3850) $PN 58
J 2
(-7085 3860);
DISPLAY 0.680851 (-7085 3860);
PAINT MONO (-7085 3860);
FORCEPROP 0 LASTPIN (-7075 3400) $PN 89
J 2
(-7085 3410);
DISPLAY 0.680851 (-7085 3410);
PAINT MONO (-7085 3410);
FORCEPROP 0 LASTPIN (-7075 3900) $PN 60
J 2
(-7085 3910);
DISPLAY 0.680851 (-7085 3910);
PAINT MONO (-7085 3910);
FORCEPROP 0 LASTPIN (-7075 3450) $PN 91
J 2
(-7085 3460);
DISPLAY 0.680851 (-7085 3460);
PAINT MONO (-7085 3460);
FORCEPROP 0 LASTPIN (-7075 3950) $PN 203
J 2
(-7085 3960);
DISPLAY 0.680851 (-7085 3960);
PAINT MONO (-7085 3960);
FORCEPROP 0 LASTPIN (-7075 3500) $PN 234
J 2
(-7085 3510);
DISPLAY 0.680851 (-7085 3510);
PAINT MONO (-7085 3510);
FORCEPROP 0 LASTPIN (-7075 4000) $PN 205
J 2
(-7085 4010);
DISPLAY 0.680851 (-7085 4010);
PAINT MONO (-7085 4010);
FORCEPROP 0 LASTPIN (-7075 3550) $PN 236
J 2
(-7085 3560);
DISPLAY 0.680851 (-7085 3560);
PAINT MONO (-7085 3560);
FORCEPROP 0 LASTPIN (-7075 4100) $PN 218
J 2
(-7085 4110);
DISPLAY 0.680851 (-7085 4110);
PAINT MONO (-7085 4110);
FORCEPROP 0 LASTPIN (-7075 4150) $PN 217
J 2
(-7085 4160);
DISPLAY 0.680851 (-7085 4160);
PAINT MONO (-7085 4160);
FORCEPROP 0 LASTPIN (-7075 4400) $PN 64
J 2
(-7085 4410);
DISPLAY 0.680851 (-7085 4410);
PAINT MONO (-7085 4410);
FORCEPROP 0 LASTPIN (-7075 4250) $PN 84
J 2
(-7085 4260);
DISPLAY 0.680851 (-7085 4260);
PAINT MONO (-7085 4260);
FORCEPROP 0 LASTPIN (-7075 4450) $PN 209
J 2
(-7085 4460);
DISPLAY 0.680851 (-7085 4460);
PAINT MONO (-7085 4460);
FORCEPROP 0 LASTPIN (-7075 4300) $PN 229
J 2
(-7085 4310);
DISPLAY 0.680851 (-7085 4310);
PAINT MONO (-7085 4310);
FORCEPROP 0 LASTPIN (-5875 3850) $PN 7
J 0
(-5865 3860);
DISPLAY 0.680851 (-5865 3860);
PAINT MONO (-5865 3860);
FORCEPROP 0 LASTPIN (-5875 2200) $PN 100
J 0
(-5865 2210);
DISPLAY 0.680851 (-5865 2210);
PAINT MONO (-5865 2210);
FORCEPROP 0 LASTPIN (-5875 3900) $PN 9
J 0
(-5865 3910);
DISPLAY 0.680851 (-5865 3910);
PAINT MONO (-5865 3910);
FORCEPROP 0 LASTPIN (-5875 2250) $PN 102
J 0
(-5865 2260);
DISPLAY 0.680851 (-5865 2260);
PAINT MONO (-5865 2260);
FORCEPROP 0 LASTPIN (-5875 3950) $PN 152
J 0
(-5865 3960);
DISPLAY 0.680851 (-5865 3960);
PAINT MONO (-5865 3960);
FORCEPROP 0 LASTPIN (-5875 2300) $PN 245
J 0
(-5865 2310);
DISPLAY 0.680851 (-5865 2310);
PAINT MONO (-5865 2310);
FORCEPROP 0 LASTPIN (-5875 4000) $PN 154
J 0
(-5865 4010);
DISPLAY 0.680851 (-5865 4010);
PAINT MONO (-5865 4010);
FORCEPROP 0 LASTPIN (-5875 2350) $PN 247
J 0
(-5865 2360);
DISPLAY 0.680851 (-5865 2360);
PAINT MONO (-5865 2360);
FORCEPROP 0 LASTPIN (-5875 4050) $PN 14
J 0
(-5865 4060);
DISPLAY 0.680851 (-5865 4060);
PAINT MONO (-5865 4060);
FORCEPROP 0 LASTPIN (-5875 2400) $PN 107
J 0
(-5865 2410);
DISPLAY 0.680851 (-5865 2410);
PAINT MONO (-5865 2410);
FORCEPROP 0 LASTPIN (-5875 4100) $PN 16
J 0
(-5865 4110);
DISPLAY 0.680851 (-5865 4110);
PAINT MONO (-5865 4110);
FORCEPROP 0 LASTPIN (-5875 2450) $PN 109
J 0
(-5865 2460);
DISPLAY 0.680851 (-5865 2460);
PAINT MONO (-5865 2460);
FORCEPROP 0 LASTPIN (-5875 4150) $PN 159
J 0
(-5865 4160);
DISPLAY 0.680851 (-5865 4160);
PAINT MONO (-5865 4160);
FORCEPROP 0 LASTPIN (-5875 2500) $PN 252
J 0
(-5865 2510);
DISPLAY 0.680851 (-5865 2510);
PAINT MONO (-5865 2510);
FORCEPROP 0 LASTPIN (-5875 4200) $PN 161
J 0
(-5865 4210);
DISPLAY 0.680851 (-5865 4210);
PAINT MONO (-5865 4210);
FORCEPROP 0 LASTPIN (-5875 2550) $PN 254
J 0
(-5865 2560);
DISPLAY 0.680851 (-5865 2560);
PAINT MONO (-5865 2560);
FORCEPROP 0 LASTPIN (-5875 4250) $PN 18
J 0
(-5865 4260);
DISPLAY 0.680851 (-5865 4260);
PAINT MONO (-5865 4260);
FORCEPROP 0 LASTPIN (-5875 2600) $PN 111
J 0
(-5865 2610);
DISPLAY 0.680851 (-5865 2610);
PAINT MONO (-5865 2610);
FORCEPROP 0 LASTPIN (-5875 4300) $PN 20
J 0
(-5865 4310);
DISPLAY 0.680851 (-5865 4310);
PAINT MONO (-5865 4310);
FORCEPROP 0 LASTPIN (-5875 2650) $PN 113
J 0
(-5865 2660);
DISPLAY 0.680851 (-5865 2660);
PAINT MONO (-5865 2660);
FORCEPROP 0 LASTPIN (-5875 4350) $PN 163
J 0
(-5865 4360);
DISPLAY 0.680851 (-5865 4360);
PAINT MONO (-5865 4360);
FORCEPROP 0 LASTPIN (-5875 2700) $PN 256
J 0
(-5865 2710);
DISPLAY 0.680851 (-5865 2710);
PAINT MONO (-5865 2710);
FORCEPROP 0 LASTPIN (-5875 4400) $PN 165
J 0
(-5865 4410);
DISPLAY 0.680851 (-5865 4410);
PAINT MONO (-5865 4410);
FORCEPROP 0 LASTPIN (-5875 2750) $PN 258
J 0
(-5865 2760);
DISPLAY 0.680851 (-5865 2760);
PAINT MONO (-5865 2760);
FORCEPROP 0 LASTPIN (-5875 4450) $PN 25
J 0
(-5865 4460);
DISPLAY 0.680851 (-5865 4460);
PAINT MONO (-5865 4460);
FORCEPROP 0 LASTPIN (-5875 2800) $PN 118
J 0
(-5865 2810);
DISPLAY 0.680851 (-5865 2810);
PAINT MONO (-5865 2810);
FORCEPROP 0 LASTPIN (-5875 4500) $PN 27
J 0
(-5865 4510);
DISPLAY 0.680851 (-5865 4510);
PAINT MONO (-5865 4510);
FORCEPROP 0 LASTPIN (-5875 2850) $PN 120
J 0
(-5865 2860);
DISPLAY 0.680851 (-5865 2860);
PAINT MONO (-5865 2860);
FORCEPROP 0 LASTPIN (-5875 4550) $PN 170
J 0
(-5865 4560);
DISPLAY 0.680851 (-5865 4560);
PAINT MONO (-5865 4560);
FORCEPROP 0 LASTPIN (-5875 2900) $PN 263
J 0
(-5865 2910);
DISPLAY 0.680851 (-5865 2910);
PAINT MONO (-5865 2910);
FORCEPROP 0 LASTPIN (-5875 4600) $PN 172
J 0
(-5865 4610);
DISPLAY 0.680851 (-5865 4610);
PAINT MONO (-5865 4610);
FORCEPROP 0 LASTPIN (-5875 2950) $PN 265
J 0
(-5865 2960);
DISPLAY 0.680851 (-5865 2960);
PAINT MONO (-5865 2960);
FORCEPROP 0 LASTPIN (-5875 4650) $PN 29
J 0
(-5865 4660);
DISPLAY 0.680851 (-5865 4660);
PAINT MONO (-5865 4660);
FORCEPROP 0 LASTPIN (-5875 3000) $PN 122
J 0
(-5865 3010);
DISPLAY 0.680851 (-5865 3010);
PAINT MONO (-5865 3010);
FORCEPROP 0 LASTPIN (-5875 4700) $PN 31
J 0
(-5865 4710);
DISPLAY 0.680851 (-5865 4710);
PAINT MONO (-5865 4710);
FORCEPROP 0 LASTPIN (-5875 3050) $PN 124
J 0
(-5865 3060);
DISPLAY 0.680851 (-5865 3060);
PAINT MONO (-5865 3060);
FORCEPROP 0 LASTPIN (-5875 4750) $PN 174
J 0
(-5865 4760);
DISPLAY 0.680851 (-5865 4760);
PAINT MONO (-5865 4760);
FORCEPROP 0 LASTPIN (-5875 3100) $PN 267
J 0
(-5865 3110);
DISPLAY 0.680851 (-5865 3110);
PAINT MONO (-5865 3110);
FORCEPROP 0 LASTPIN (-5875 4800) $PN 176
J 0
(-5865 4810);
DISPLAY 0.680851 (-5865 4810);
PAINT MONO (-5865 4810);
FORCEPROP 0 LASTPIN (-5875 3150) $PN 269
J 0
(-5865 3160);
DISPLAY 0.680851 (-5865 3160);
PAINT MONO (-5865 3160);
FORCEPROP 0 LASTPIN (-5875 4850) $PN 36
J 0
(-5865 4860);
DISPLAY 0.680851 (-5865 4860);
PAINT MONO (-5865 4860);
FORCEPROP 0 LASTPIN (-5875 3200) $PN 129
J 0
(-5865 3210);
DISPLAY 0.680851 (-5865 3210);
PAINT MONO (-5865 3210);
FORCEPROP 0 LASTPIN (-5875 4900) $PN 38
J 0
(-5865 4910);
DISPLAY 0.680851 (-5865 4910);
PAINT MONO (-5865 4910);
FORCEPROP 0 LASTPIN (-5875 3250) $PN 131
J 0
(-5865 3260);
DISPLAY 0.680851 (-5865 3260);
PAINT MONO (-5865 3260);
FORCEPROP 0 LASTPIN (-5875 4950) $PN 181
J 0
(-5865 4960);
DISPLAY 0.680851 (-5865 4960);
PAINT MONO (-5865 4960);
FORCEPROP 0 LASTPIN (-5875 3300) $PN 274
J 0
(-5865 3310);
DISPLAY 0.680851 (-5865 3310);
PAINT MONO (-5865 3310);
FORCEPROP 0 LASTPIN (-5875 5000) $PN 183
J 0
(-5865 5010);
DISPLAY 0.680851 (-5865 5010);
PAINT MONO (-5865 5010);
FORCEPROP 0 LASTPIN (-5875 3350) $PN 276
J 0
(-5865 3360);
DISPLAY 0.680851 (-5865 3360);
PAINT MONO (-5865 3360);
FORCEPROP 0 LASTPIN (-5875 5050) $PN 40
J 0
(-5865 5060);
DISPLAY 0.680851 (-5865 5060);
PAINT MONO (-5865 5060);
FORCEPROP 0 LASTPIN (-5875 3400) $PN 133
J 0
(-5865 3410);
DISPLAY 0.680851 (-5865 3410);
PAINT MONO (-5865 3410);
FORCEPROP 0 LASTPIN (-5875 5100) $PN 42
J 0
(-5865 5110);
DISPLAY 0.680851 (-5865 5110);
PAINT MONO (-5865 5110);
FORCEPROP 0 LASTPIN (-5875 3450) $PN 135
J 0
(-5865 3460);
DISPLAY 0.680851 (-5865 3460);
PAINT MONO (-5865 3460);
FORCEPROP 0 LASTPIN (-5875 5150) $PN 185
J 0
(-5865 5160);
DISPLAY 0.680851 (-5865 5160);
PAINT MONO (-5865 5160);
FORCEPROP 0 LASTPIN (-5875 3500) $PN 278
J 0
(-5865 3510);
DISPLAY 0.680851 (-5865 3510);
PAINT MONO (-5865 3510);
FORCEPROP 0 LASTPIN (-5875 5200) $PN 187
J 0
(-5865 5210);
DISPLAY 0.680851 (-5865 5210);
PAINT MONO (-5865 5210);
FORCEPROP 0 LASTPIN (-5875 3550) $PN 280
J 0
(-5865 3560);
DISPLAY 0.680851 (-5865 3560);
PAINT MONO (-5865 3560);
FORCEPROP 0 LASTPIN (-5875 5250) $PN 47
J 0
(-5865 5260);
DISPLAY 0.680851 (-5865 5260);
PAINT MONO (-5865 5260);
FORCEPROP 0 LASTPIN (-5875 3600) $PN 140
J 0
(-5865 3610);
DISPLAY 0.680851 (-5865 3610);
PAINT MONO (-5865 3610);
FORCEPROP 0 LASTPIN (-5875 5300) $PN 49
J 0
(-5865 5310);
DISPLAY 0.680851 (-5865 5310);
PAINT MONO (-5865 5310);
FORCEPROP 0 LASTPIN (-5875 3650) $PN 142
J 0
(-5865 3660);
DISPLAY 0.680851 (-5865 3660);
PAINT MONO (-5865 3660);
FORCEPROP 0 LASTPIN (-5875 5350) $PN 192
J 0
(-5865 5360);
DISPLAY 0.680851 (-5865 5360);
PAINT MONO (-5865 5360);
FORCEPROP 0 LASTPIN (-5875 3700) $PN 285
J 0
(-5865 3710);
DISPLAY 0.680851 (-5865 3710);
PAINT MONO (-5865 3710);
FORCEPROP 0 LASTPIN (-5875 5400) $PN 194
J 0
(-5865 5410);
DISPLAY 0.680851 (-5865 5410);
PAINT MONO (-5865 5410);
FORCEPROP 0 LASTPIN (-5875 3750) $PN 287
J 0
(-5865 3760);
DISPLAY 0.680851 (-5865 3760);
PAINT MONO (-5865 3760);
FORCEPROP 0 LASTPIN (-7075 2900) $PN 148
J 2
(-7085 2910);
DISPLAY 0.680851 (-7085 2910);
PAINT MONO (-7085 2910);
FORCEPROP 0 LASTPIN (-7075 2800) $PN 4
J 2
(-7085 2810);
DISPLAY 0.680851 (-7085 2810);
PAINT MONO (-7085 2810);
FORCEPROP 0 LASTPIN (-7075 2850) $PN 5
J 2
(-7085 2860);
DISPLAY 0.680851 (-7085 2860);
PAINT MONO (-7085 2860);
FORCEPROP 0 LASTPIN (-7075 2000) $PN 86
J 2
(-7085 2010);
DISPLAY 0.680851 (-7085 2010);
PAINT MONO (-7085 2010);
FORCEPROP 0 LASTPIN (-7075 1950) $PN 87
J 2
(-7085 1960);
DISPLAY 0.680851 (-7085 1960);
PAINT MONO (-7085 1960);
FORCEPROP 0 LASTPIN (-7075 4600) $PN 74
J 2
(-7085 4610);
DISPLAY 0.680851 (-7085 4610);
PAINT MONO (-7085 4610);
FORCEPROP 0 LASTPIN (-7075 4550) $PN 227
J 2
(-7085 4560);
DISPLAY 0.680851 (-7085 4560);
PAINT MONO (-7085 4560);
FORCEPROP 0 LASTPIN (-7075 2550) $PN 147
J 2
(-7085 2560);
DISPLAY 0.680851 (-7085 2560);
PAINT MONO (-7085 2560);
FORCEPROP 0 LASTPIN (-7075 3100) $PN 207
J 2
(-7085 3110);
DISPLAY 0.680851 (-7085 3110);
PAINT MONO (-7085 3110);
FORCEPROP 0 LASTPIN (-7075 2150) $PN 2
J 2
(-7085 2160);
DISPLAY 0.680851 (-7085 2160);
PAINT MONO (-7085 2160);
FORCEPROP 0 LASTPIN (-7075 2200) $PN 144
J 2
(-7085 2210);
DISPLAY 0.680851 (-7085 2210);
PAINT MONO (-7085 2210);
FORCEPROP 0 LASTPIN (-7075 2250) $PN 149
J 2
(-7085 2260);
DISPLAY 0.680851 (-7085 2260);
PAINT MONO (-7085 2260);
FORCEPROP 0 LASTPIN (-7075 2300) $PN 150
J 2
(-7085 2310);
DISPLAY 0.680851 (-7085 2310);
PAINT MONO (-7085 2310);
FORCEPROP 0 LASTPIN (-7075 2350) $PN 220
J 2
(-7085 2360);
DISPLAY 0.680851 (-7085 2360);
PAINT MONO (-7085 2360);
FORCEPROP 0 LASTPIN (-7075 2400) $PN 231
J 2
(-7085 2410);
DISPLAY 0.680851 (-7085 2410);
PAINT MONO (-7085 2410);
FORCEPROP 0 LASTPIN (-7075 2450) $PN 232
J 2
(-7085 2460);
DISPLAY 0.680851 (-7085 2460);
PAINT MONO (-7085 2460);
FORCEPROP 0 LASTPIN (-7075 2950) $PN 3
J 2
(-7085 2960);
DISPLAY 0.680851 (-7085 2960);
PAINT MONO (-7085 2960);
FORCEPROP 1 LAST MATERIAL IO
J 0
(-6925 5575);
DISPLAY 0.468085 (-6925 5575);
PAINT SKYBLUE (-6925 5575);
FORCEPROP 1 LAST PART_NUMBER DFHST8FS479
J 0
(-6925 5650);
DISPLAY 0.468085 (-6925 5650);
PAINT SKYBLUE (-6925 5650);
FORCEPROP 2 LAST PART_TYPE SMLF
J 0
(-6925 5825);
DISPLAY 1.021277 (-6925 5825);
FORCEPROP 2 LAST VALUE SCONN288_DDR506112002KQ
J 0
(-6925 5775);
DISPLAY 0.489362 (-6925 5775);
PAINT SKYBLUE (-6925 5775);
FORCEPROP 1 LAST CDS_LMAN_SYM_OUTLINE -450,1900,450,-1850
J 0
(-6475 3650);
DISPLAY 0.468085 (-6475 3650);
PAINT GREEN (-6475 3650);
DISPLAY INVISIBLE (-6475 3650);
FORCEPROP 1 LAST PATH I22
J 0
(-6475 3650);
DISPLAY 0.723404 (-6475 3650);
PAINT GREEN (-6475 3650);
DISPLAY INVISIBLE (-6475 3650);
FORCEPROP 1 LAST NEEDS_NO_SIZE TRUE
J 0
(-6475 3650);
DISPLAY 0.723404 (-6475 3650);
PAINT GREEN (-6475 3650);
DISPLAY INVISIBLE (-6475 3650);
FORCEPROP 2 LAST CDS_LIB pure_quanta
J 0
(-6475 3650);
DISPLAY INVISIBLE (-6475 3650);
FORCEADD TAP..1
(-2900 3275);
FORCEPROP 3 LASTPIN (-2950 3275) SIG_NAME M_G_CPU0_SB_DQS_DN<7>
J 0
(-2940 3285);
DISPLAY 0.659574 (-2940 3285);
PAINT MONO (-2940 3285);
DISPLAY INVISIBLE (-2940 3285);
FORCEPROP 1 LASTPIN (-2950 3275) BN 7
J 0
(-2962 3283);
DISPLAY 0.489362 (-2962 3283);
PAINT GREEN (-2962 3283);
FORCEPROP 2 LAST CDS_LIB mstr_standard
J 0
(-2900 3275);
DISPLAY 0.723404 (-2900 3275);
PAINT MONO (-2900 3275);
DISPLAY INVISIBLE (-2900 3275);
FORCEPROP 1 LAST BODY_TYPE PLUMBING
J 0
(-2900 3325);
DISPLAY 0.872340 (-2900 3325);
PAINT GREEN (-2900 3325);
DISPLAY INVISIBLE (-2900 3325);
FORCEPROP 1 LAST HDL_TAP TRUE
J 0
(-2575 3150);
DISPLAY 0.872340 (-2575 3150);
DISPLAY INVISIBLE (-2575 3150);
FORCEPROP 1 LAST PATH I220
J 0
(-2902 3275);
DISPLAY 0.872340 (-2902 3275);
PAINT GREEN (-2902 3275);
DISPLAY INVISIBLE (-2902 3275);
FORCEADD TAP..1
(-2900 3175);
FORCEPROP 3 LASTPIN (-2950 3175) SIG_NAME M_G_CPU0_SB_DQS_DN<6>
J 0
(-2940 3185);
DISPLAY 0.659574 (-2940 3185);
PAINT MONO (-2940 3185);
DISPLAY INVISIBLE (-2940 3185);
FORCEPROP 1 LASTPIN (-2950 3175) BN 6
J 0
(-2962 3183);
DISPLAY 0.489362 (-2962 3183);
PAINT GREEN (-2962 3183);
FORCEPROP 2 LAST CDS_LIB mstr_standard
J 0
(-2900 3175);
DISPLAY 0.723404 (-2900 3175);
PAINT MONO (-2900 3175);
DISPLAY INVISIBLE (-2900 3175);
FORCEPROP 1 LAST BODY_TYPE PLUMBING
J 0
(-2900 3225);
DISPLAY 0.872340 (-2900 3225);
PAINT GREEN (-2900 3225);
DISPLAY INVISIBLE (-2900 3225);
FORCEPROP 1 LAST HDL_TAP TRUE
J 0
(-2575 3050);
DISPLAY 0.872340 (-2575 3050);
DISPLAY INVISIBLE (-2575 3050);
FORCEPROP 1 LAST PATH I221
J 0
(-2902 3175);
DISPLAY 0.872340 (-2902 3175);
PAINT GREEN (-2902 3175);
DISPLAY INVISIBLE (-2902 3175);
FORCEADD TAP..1
(-2900 3075);
FORCEPROP 3 LASTPIN (-2950 3075) SIG_NAME M_G_CPU0_SB_DQS_DN<5>
J 0
(-2940 3085);
DISPLAY 0.659574 (-2940 3085);
PAINT MONO (-2940 3085);
DISPLAY INVISIBLE (-2940 3085);
FORCEPROP 1 LASTPIN (-2950 3075) BN 5
J 0
(-2962 3083);
DISPLAY 0.489362 (-2962 3083);
PAINT GREEN (-2962 3083);
FORCEPROP 2 LAST CDS_LIB mstr_standard
J 0
(-2900 3075);
DISPLAY 0.723404 (-2900 3075);
PAINT MONO (-2900 3075);
DISPLAY INVISIBLE (-2900 3075);
FORCEPROP 1 LAST BODY_TYPE PLUMBING
J 0
(-2900 3125);
DISPLAY 0.872340 (-2900 3125);
PAINT GREEN (-2900 3125);
DISPLAY INVISIBLE (-2900 3125);
FORCEPROP 1 LAST HDL_TAP TRUE
J 0
(-2575 2950);
DISPLAY 0.872340 (-2575 2950);
DISPLAY INVISIBLE (-2575 2950);
FORCEPROP 1 LAST PATH I222
J 0
(-2902 3075);
DISPLAY 0.872340 (-2902 3075);
PAINT GREEN (-2902 3075);
DISPLAY INVISIBLE (-2902 3075);
FORCEADD TAP..1
(-2900 2975);
FORCEPROP 3 LASTPIN (-2950 2975) SIG_NAME M_G_CPU0_SB_DQS_DN<4>
J 0
(-2940 2985);
DISPLAY 0.659574 (-2940 2985);
PAINT MONO (-2940 2985);
DISPLAY INVISIBLE (-2940 2985);
FORCEPROP 1 LASTPIN (-2950 2975) BN 4
J 0
(-2962 2983);
DISPLAY 0.489362 (-2962 2983);
PAINT GREEN (-2962 2983);
FORCEPROP 2 LAST CDS_LIB mstr_standard
J 0
(-2900 2975);
DISPLAY 0.723404 (-2900 2975);
PAINT MONO (-2900 2975);
DISPLAY INVISIBLE (-2900 2975);
FORCEPROP 1 LAST BODY_TYPE PLUMBING
J 0
(-2900 3025);
DISPLAY 0.872340 (-2900 3025);
PAINT GREEN (-2900 3025);
DISPLAY INVISIBLE (-2900 3025);
FORCEPROP 1 LAST HDL_TAP TRUE
J 0
(-2575 2850);
DISPLAY 0.872340 (-2575 2850);
DISPLAY INVISIBLE (-2575 2850);
FORCEPROP 1 LAST PATH I223
J 0
(-2902 2975);
DISPLAY 0.872340 (-2902 2975);
PAINT GREEN (-2902 2975);
DISPLAY INVISIBLE (-2902 2975);
FORCEADD TAP..1
(-2900 2875);
FORCEPROP 3 LASTPIN (-2950 2875) SIG_NAME M_G_CPU0_SB_DQS_DN<3>
J 0
(-2940 2885);
DISPLAY 0.659574 (-2940 2885);
PAINT MONO (-2940 2885);
DISPLAY INVISIBLE (-2940 2885);
FORCEPROP 1 LASTPIN (-2950 2875) BN 3
J 0
(-2962 2883);
DISPLAY 0.489362 (-2962 2883);
PAINT GREEN (-2962 2883);
FORCEPROP 2 LAST CDS_LIB mstr_standard
J 0
(-2900 2875);
DISPLAY 0.723404 (-2900 2875);
PAINT MONO (-2900 2875);
DISPLAY INVISIBLE (-2900 2875);
FORCEPROP 1 LAST BODY_TYPE PLUMBING
J 0
(-2900 2925);
DISPLAY 0.872340 (-2900 2925);
PAINT GREEN (-2900 2925);
DISPLAY INVISIBLE (-2900 2925);
FORCEPROP 1 LAST HDL_TAP TRUE
J 0
(-2575 2750);
DISPLAY 0.872340 (-2575 2750);
DISPLAY INVISIBLE (-2575 2750);
FORCEPROP 1 LAST PATH I224
J 0
(-2902 2875);
DISPLAY 0.872340 (-2902 2875);
PAINT GREEN (-2902 2875);
DISPLAY INVISIBLE (-2902 2875);
FORCEADD TAP..1
(-3100 3225);
FORCEPROP 3 LASTPIN (-3150 3225) SIG_NAME M_G_CPU0_SB_DQS_DP<6>
J 0
(-3140 3235);
DISPLAY 0.659574 (-3140 3235);
PAINT MONO (-3140 3235);
DISPLAY INVISIBLE (-3140 3235);
FORCEPROP 1 LASTPIN (-3150 3225) BN 6
J 0
(-3162 3233);
DISPLAY 0.489362 (-3162 3233);
PAINT GREEN (-3162 3233);
FORCEPROP 2 LAST CDS_LIB mstr_standard
J 0
(-3100 3225);
DISPLAY 0.723404 (-3100 3225);
PAINT MONO (-3100 3225);
DISPLAY INVISIBLE (-3100 3225);
FORCEPROP 1 LAST BODY_TYPE PLUMBING
J 0
(-3100 3275);
DISPLAY 0.872340 (-3100 3275);
PAINT GREEN (-3100 3275);
DISPLAY INVISIBLE (-3100 3275);
FORCEPROP 1 LAST HDL_TAP TRUE
J 0
(-2775 3100);
DISPLAY 0.872340 (-2775 3100);
DISPLAY INVISIBLE (-2775 3100);
FORCEPROP 1 LAST PATH I225
J 0
(-3102 3225);
DISPLAY 0.872340 (-3102 3225);
PAINT GREEN (-3102 3225);
DISPLAY INVISIBLE (-3102 3225);
FORCEADD TAP..1
(-3100 3325);
FORCEPROP 3 LASTPIN (-3150 3325) SIG_NAME M_G_CPU0_SB_DQS_DP<7>
J 0
(-3140 3335);
DISPLAY 0.659574 (-3140 3335);
PAINT MONO (-3140 3335);
DISPLAY INVISIBLE (-3140 3335);
FORCEPROP 1 LASTPIN (-3150 3325) BN 7
J 0
(-3162 3333);
DISPLAY 0.489362 (-3162 3333);
PAINT GREEN (-3162 3333);
FORCEPROP 2 LAST CDS_LIB mstr_standard
J 0
(-3100 3325);
DISPLAY 0.723404 (-3100 3325);
PAINT MONO (-3100 3325);
DISPLAY INVISIBLE (-3100 3325);
FORCEPROP 1 LAST BODY_TYPE PLUMBING
J 0
(-3100 3375);
DISPLAY 0.872340 (-3100 3375);
PAINT GREEN (-3100 3375);
DISPLAY INVISIBLE (-3100 3375);
FORCEPROP 1 LAST HDL_TAP TRUE
J 0
(-2775 3200);
DISPLAY 0.872340 (-2775 3200);
DISPLAY INVISIBLE (-2775 3200);
FORCEPROP 1 LAST PATH I226
J 0
(-3102 3325);
DISPLAY 0.872340 (-3102 3325);
PAINT GREEN (-3102 3325);
DISPLAY INVISIBLE (-3102 3325);
FORCEADD TAP..1
(-3100 3125);
FORCEPROP 3 LASTPIN (-3150 3125) SIG_NAME M_G_CPU0_SB_DQS_DP<5>
J 0
(-3140 3135);
DISPLAY 0.659574 (-3140 3135);
PAINT MONO (-3140 3135);
DISPLAY INVISIBLE (-3140 3135);
FORCEPROP 1 LASTPIN (-3150 3125) BN 5
J 0
(-3162 3133);
DISPLAY 0.489362 (-3162 3133);
PAINT GREEN (-3162 3133);
FORCEPROP 2 LAST CDS_LIB mstr_standard
J 0
(-3100 3125);
DISPLAY 0.723404 (-3100 3125);
PAINT MONO (-3100 3125);
DISPLAY INVISIBLE (-3100 3125);
FORCEPROP 1 LAST BODY_TYPE PLUMBING
J 0
(-3100 3175);
DISPLAY 0.872340 (-3100 3175);
PAINT GREEN (-3100 3175);
DISPLAY INVISIBLE (-3100 3175);
FORCEPROP 1 LAST HDL_TAP TRUE
J 0
(-2775 3000);
DISPLAY 0.872340 (-2775 3000);
DISPLAY INVISIBLE (-2775 3000);
FORCEPROP 1 LAST PATH I227
J 0
(-3102 3125);
DISPLAY 0.872340 (-3102 3125);
PAINT GREEN (-3102 3125);
DISPLAY INVISIBLE (-3102 3125);
FORCEADD TAP..1
(-3100 3025);
FORCEPROP 3 LASTPIN (-3150 3025) SIG_NAME M_G_CPU0_SB_DQS_DP<4>
J 0
(-3140 3035);
DISPLAY 0.659574 (-3140 3035);
PAINT MONO (-3140 3035);
DISPLAY INVISIBLE (-3140 3035);
FORCEPROP 1 LASTPIN (-3150 3025) BN 4
J 0
(-3162 3033);
DISPLAY 0.489362 (-3162 3033);
PAINT GREEN (-3162 3033);
FORCEPROP 2 LAST CDS_LIB mstr_standard
J 0
(-3100 3025);
DISPLAY 0.723404 (-3100 3025);
PAINT MONO (-3100 3025);
DISPLAY INVISIBLE (-3100 3025);
FORCEPROP 1 LAST BODY_TYPE PLUMBING
J 0
(-3100 3075);
DISPLAY 0.872340 (-3100 3075);
PAINT GREEN (-3100 3075);
DISPLAY INVISIBLE (-3100 3075);
FORCEPROP 1 LAST HDL_TAP TRUE
J 0
(-2775 2900);
DISPLAY 0.872340 (-2775 2900);
DISPLAY INVISIBLE (-2775 2900);
FORCEPROP 1 LAST PATH I228
J 0
(-3102 3025);
DISPLAY 0.872340 (-3102 3025);
PAINT GREEN (-3102 3025);
DISPLAY INVISIBLE (-3102 3025);
FORCEADD TAP..1
(-3100 2925);
FORCEPROP 3 LASTPIN (-3150 2925) SIG_NAME M_G_CPU0_SB_DQS_DP<3>
J 0
(-3140 2935);
DISPLAY 0.659574 (-3140 2935);
PAINT MONO (-3140 2935);
DISPLAY INVISIBLE (-3140 2935);
FORCEPROP 1 LASTPIN (-3150 2925) BN 3
J 0
(-3162 2933);
DISPLAY 0.489362 (-3162 2933);
PAINT GREEN (-3162 2933);
FORCEPROP 2 LAST CDS_LIB mstr_standard
J 0
(-3100 2925);
DISPLAY 0.723404 (-3100 2925);
PAINT MONO (-3100 2925);
DISPLAY INVISIBLE (-3100 2925);
FORCEPROP 1 LAST BODY_TYPE PLUMBING
J 0
(-3100 2975);
DISPLAY 0.872340 (-3100 2975);
PAINT GREEN (-3100 2975);
DISPLAY INVISIBLE (-3100 2975);
FORCEPROP 1 LAST HDL_TAP TRUE
J 0
(-2775 2800);
DISPLAY 0.872340 (-2775 2800);
DISPLAY INVISIBLE (-2775 2800);
FORCEPROP 1 LAST PATH I229
J 0
(-3102 2925);
DISPLAY 0.872340 (-3102 2925);
PAINT GREEN (-3102 2925);
DISPLAY INVISIBLE (-3102 2925);
FORCEADD TAP..1
R 2
(-7325 3200);
FORCEPROP 3 LASTPIN (-7275 3200) SIG_NAME M_G_CPU0_SB_CB<0>
J 0
(-7265 3210);
DISPLAY 0.659574 (-7265 3210);
PAINT MONO (-7265 3210);
DISPLAY INVISIBLE (-7265 3210);
FORCEPROP 1 LASTPIN (-7275 3200) BN 0
J 2
(-7263 3208);
DISPLAY 0.489362 (-7263 3208);
PAINT GREEN (-7263 3208);
FORCEPROP 2 LAST CDS_LIB mstr_standard
J 0
(-7325 3200);
DISPLAY 0.723404 (-7325 3200);
PAINT MONO (-7325 3200);
DISPLAY INVISIBLE (-7325 3200);
FORCEPROP 1 LAST BODY_TYPE PLUMBING
J 2
(-7325 3250);
DISPLAY 0.872340 (-7325 3250);
PAINT GREEN (-7325 3250);
DISPLAY INVISIBLE (-7325 3250);
FORCEPROP 1 LAST HDL_TAP TRUE
J 2
(-7650 3075);
DISPLAY 0.872340 (-7650 3075);
DISPLAY INVISIBLE (-7650 3075);
FORCEPROP 1 LAST PATH I23
J 2
(-7323 3200);
DISPLAY 0.872340 (-7323 3200);
PAINT GREEN (-7323 3200);
DISPLAY INVISIBLE (-7323 3200);
FORCEADD TAP..1
(-2900 2775);
FORCEPROP 3 LASTPIN (-2950 2775) SIG_NAME M_G_CPU0_SB_DQS_DN<2>
J 0
(-2940 2785);
DISPLAY 0.659574 (-2940 2785);
PAINT MONO (-2940 2785);
DISPLAY INVISIBLE (-2940 2785);
FORCEPROP 1 LASTPIN (-2950 2775) BN 2
J 0
(-2962 2783);
DISPLAY 0.489362 (-2962 2783);
PAINT GREEN (-2962 2783);
FORCEPROP 2 LAST CDS_LIB mstr_standard
J 0
(-2900 2775);
DISPLAY 0.723404 (-2900 2775);
PAINT MONO (-2900 2775);
DISPLAY INVISIBLE (-2900 2775);
FORCEPROP 1 LAST BODY_TYPE PLUMBING
J 0
(-2900 2825);
DISPLAY 0.872340 (-2900 2825);
PAINT GREEN (-2900 2825);
DISPLAY INVISIBLE (-2900 2825);
FORCEPROP 1 LAST HDL_TAP TRUE
J 0
(-2575 2650);
DISPLAY 0.872340 (-2575 2650);
DISPLAY INVISIBLE (-2575 2650);
FORCEPROP 1 LAST PATH I230
J 0
(-2902 2775);
DISPLAY 0.872340 (-2902 2775);
PAINT GREEN (-2902 2775);
DISPLAY INVISIBLE (-2902 2775);
FORCEADD TAP..1
(-2900 2675);
FORCEPROP 3 LASTPIN (-2950 2675) SIG_NAME M_G_CPU0_SB_DQS_DN<1>
J 0
(-2940 2685);
DISPLAY 0.659574 (-2940 2685);
PAINT MONO (-2940 2685);
DISPLAY INVISIBLE (-2940 2685);
FORCEPROP 1 LASTPIN (-2950 2675) BN 1
J 0
(-2962 2683);
DISPLAY 0.489362 (-2962 2683);
PAINT GREEN (-2962 2683);
FORCEPROP 2 LAST CDS_LIB mstr_standard
J 0
(-2900 2675);
DISPLAY 0.723404 (-2900 2675);
PAINT MONO (-2900 2675);
DISPLAY INVISIBLE (-2900 2675);
FORCEPROP 1 LAST BODY_TYPE PLUMBING
J 0
(-2900 2725);
DISPLAY 0.872340 (-2900 2725);
PAINT GREEN (-2900 2725);
DISPLAY INVISIBLE (-2900 2725);
FORCEPROP 1 LAST HDL_TAP TRUE
J 0
(-2575 2550);
DISPLAY 0.872340 (-2575 2550);
DISPLAY INVISIBLE (-2575 2550);
FORCEPROP 1 LAST PATH I231
J 0
(-2902 2675);
DISPLAY 0.872340 (-2902 2675);
PAINT GREEN (-2902 2675);
DISPLAY INVISIBLE (-2902 2675);
FORCEADD TAP..1
(-2900 2575);
FORCEPROP 3 LASTPIN (-2950 2575) SIG_NAME M_G_CPU0_SB_DQS_DN<0>
J 0
(-2940 2585);
DISPLAY 0.659574 (-2940 2585);
PAINT MONO (-2940 2585);
DISPLAY INVISIBLE (-2940 2585);
FORCEPROP 1 LASTPIN (-2950 2575) BN 0
J 0
(-2962 2583);
DISPLAY 0.489362 (-2962 2583);
PAINT GREEN (-2962 2583);
FORCEPROP 2 LAST CDS_LIB mstr_standard
J 0
(-2900 2575);
DISPLAY 0.723404 (-2900 2575);
PAINT MONO (-2900 2575);
DISPLAY INVISIBLE (-2900 2575);
FORCEPROP 1 LAST BODY_TYPE PLUMBING
J 0
(-2900 2625);
DISPLAY 0.872340 (-2900 2625);
PAINT GREEN (-2900 2625);
DISPLAY INVISIBLE (-2900 2625);
FORCEPROP 1 LAST HDL_TAP TRUE
J 0
(-2575 2450);
DISPLAY 0.872340 (-2575 2450);
DISPLAY INVISIBLE (-2575 2450);
FORCEPROP 1 LAST PATH I232
J 0
(-2902 2575);
DISPLAY 0.872340 (-2902 2575);
PAINT GREEN (-2902 2575);
DISPLAY INVISIBLE (-2902 2575);
FORCEADD TAP..1
(-3100 2625);
FORCEPROP 3 LASTPIN (-3150 2625) SIG_NAME M_G_CPU0_SB_DQS_DP<0>
J 0
(-3140 2635);
DISPLAY 0.659574 (-3140 2635);
PAINT MONO (-3140 2635);
DISPLAY INVISIBLE (-3140 2635);
FORCEPROP 1 LASTPIN (-3150 2625) BN 0
J 0
(-3162 2633);
DISPLAY 0.489362 (-3162 2633);
PAINT GREEN (-3162 2633);
FORCEPROP 2 LAST CDS_LIB mstr_standard
J 0
(-3100 2625);
DISPLAY 0.723404 (-3100 2625);
PAINT MONO (-3100 2625);
DISPLAY INVISIBLE (-3100 2625);
FORCEPROP 1 LAST BODY_TYPE PLUMBING
J 0
(-3100 2675);
DISPLAY 0.872340 (-3100 2675);
PAINT GREEN (-3100 2675);
DISPLAY INVISIBLE (-3100 2675);
FORCEPROP 1 LAST HDL_TAP TRUE
J 0
(-2775 2500);
DISPLAY 0.872340 (-2775 2500);
DISPLAY INVISIBLE (-2775 2500);
FORCEPROP 1 LAST PATH I233
J 0
(-3102 2625);
DISPLAY 0.872340 (-3102 2625);
PAINT GREEN (-3102 2625);
DISPLAY INVISIBLE (-3102 2625);
FORCEADD TAP..1
(-3100 2725);
FORCEPROP 3 LASTPIN (-3150 2725) SIG_NAME M_G_CPU0_SB_DQS_DP<1>
J 0
(-3140 2735);
DISPLAY 0.659574 (-3140 2735);
PAINT MONO (-3140 2735);
DISPLAY INVISIBLE (-3140 2735);
FORCEPROP 1 LASTPIN (-3150 2725) BN 1
J 0
(-3162 2733);
DISPLAY 0.489362 (-3162 2733);
PAINT GREEN (-3162 2733);
FORCEPROP 2 LAST CDS_LIB mstr_standard
J 0
(-3100 2725);
DISPLAY 0.723404 (-3100 2725);
PAINT MONO (-3100 2725);
DISPLAY INVISIBLE (-3100 2725);
FORCEPROP 1 LAST BODY_TYPE PLUMBING
J 0
(-3100 2775);
DISPLAY 0.872340 (-3100 2775);
PAINT GREEN (-3100 2775);
DISPLAY INVISIBLE (-3100 2775);
FORCEPROP 1 LAST HDL_TAP TRUE
J 0
(-2775 2600);
DISPLAY 0.872340 (-2775 2600);
DISPLAY INVISIBLE (-2775 2600);
FORCEPROP 1 LAST PATH I234
J 0
(-3102 2725);
DISPLAY 0.872340 (-3102 2725);
PAINT GREEN (-3102 2725);
DISPLAY INVISIBLE (-3102 2725);
FORCEADD TAP..1
(-3100 2825);
FORCEPROP 3 LASTPIN (-3150 2825) SIG_NAME M_G_CPU0_SB_DQS_DP<2>
J 0
(-3140 2835);
DISPLAY 0.659574 (-3140 2835);
PAINT MONO (-3140 2835);
DISPLAY INVISIBLE (-3140 2835);
FORCEPROP 1 LASTPIN (-3150 2825) BN 2
J 0
(-3162 2833);
DISPLAY 0.489362 (-3162 2833);
PAINT GREEN (-3162 2833);
FORCEPROP 2 LAST CDS_LIB mstr_standard
J 0
(-3100 2825);
DISPLAY 0.723404 (-3100 2825);
PAINT MONO (-3100 2825);
DISPLAY INVISIBLE (-3100 2825);
FORCEPROP 1 LAST BODY_TYPE PLUMBING
J 0
(-3100 2875);
DISPLAY 0.872340 (-3100 2875);
PAINT GREEN (-3100 2875);
DISPLAY INVISIBLE (-3100 2875);
FORCEPROP 1 LAST HDL_TAP TRUE
J 0
(-2775 2700);
DISPLAY 0.872340 (-2775 2700);
DISPLAY INVISIBLE (-2775 2700);
FORCEPROP 1 LAST PATH I235
J 0
(-3102 2825);
DISPLAY 0.872340 (-3102 2825);
PAINT GREEN (-3102 2825);
DISPLAY INVISIBLE (-3102 2825);
FORCEADD SCONN288_DDR506112002KQ..2
(-4100 3575);
FORCEPROP 1 LAST LOCATION J16
J 0
(-4700 4900);
DISPLAY 0.468085 (-4700 4900);
PAINT SKYBLUE (-4700 4900);
FORCEPROP 0 LAST $SEC 2
J 0
(-4550 5050);
DISPLAY 0.680851 (-4550 5050);
PAINT MONO (-4550 5050);
DISPLAY INVISIBLE (-4550 5050);
FORCEPROP 2 LAST CDS_SEC 2
J 0
(-4550 5050);
DISPLAY 0.680851 (-4550 5050);
DISPLAY INVISIBLE (-4550 5050);
FORCEPROP 0 LASTPIN (-3350 3625) $PN 12
J 0
(-3340 3635);
DISPLAY 0.680851 (-3340 3635);
PAINT MONO (-3340 3635);
FORCEPROP 0 LASTPIN (-3350 3675) $PN 11
J 0
(-3340 3685);
DISPLAY 0.680851 (-3340 3685);
PAINT MONO (-3340 3685);
FORCEPROP 0 LASTPIN (-3350 2575) $PN 105
J 0
(-3340 2585);
DISPLAY 0.680851 (-3340 2585);
PAINT MONO (-3340 2585);
FORCEPROP 0 LASTPIN (-3350 2625) $PN 104
J 0
(-3340 2635);
DISPLAY 0.680851 (-3340 2635);
PAINT MONO (-3340 2635);
FORCEPROP 0 LASTPIN (-3350 3725) $PN 23
J 0
(-3340 3735);
DISPLAY 0.680851 (-3340 3735);
PAINT MONO (-3340 3735);
FORCEPROP 0 LASTPIN (-3350 3775) $PN 22
J 0
(-3340 3785);
DISPLAY 0.680851 (-3340 3785);
PAINT MONO (-3340 3785);
FORCEPROP 0 LASTPIN (-3350 2675) $PN 116
J 0
(-3340 2685);
DISPLAY 0.680851 (-3340 2685);
PAINT MONO (-3340 2685);
FORCEPROP 0 LASTPIN (-3350 2725) $PN 115
J 0
(-3340 2735);
DISPLAY 0.680851 (-3340 2735);
PAINT MONO (-3340 2735);
FORCEPROP 0 LASTPIN (-3350 3825) $PN 34
J 0
(-3340 3835);
DISPLAY 0.680851 (-3340 3835);
PAINT MONO (-3340 3835);
FORCEPROP 0 LASTPIN (-3350 3875) $PN 33
J 0
(-3340 3885);
DISPLAY 0.680851 (-3340 3885);
PAINT MONO (-3340 3885);
FORCEPROP 0 LASTPIN (-3350 2775) $PN 127
J 0
(-3340 2785);
DISPLAY 0.680851 (-3340 2785);
PAINT MONO (-3340 2785);
FORCEPROP 0 LASTPIN (-3350 2825) $PN 126
J 0
(-3340 2835);
DISPLAY 0.680851 (-3340 2835);
PAINT MONO (-3340 2835);
FORCEPROP 0 LASTPIN (-3350 3925) $PN 45
J 0
(-3340 3935);
DISPLAY 0.680851 (-3340 3935);
PAINT MONO (-3340 3935);
FORCEPROP 0 LASTPIN (-3350 3975) $PN 44
J 0
(-3340 3985);
DISPLAY 0.680851 (-3340 3985);
PAINT MONO (-3340 3985);
FORCEPROP 0 LASTPIN (-3350 2875) $PN 138
J 0
(-3340 2885);
DISPLAY 0.680851 (-3340 2885);
PAINT MONO (-3340 2885);
FORCEPROP 0 LASTPIN (-3350 2925) $PN 137
J 0
(-3340 2935);
DISPLAY 0.680851 (-3340 2935);
PAINT MONO (-3340 2935);
FORCEPROP 0 LASTPIN (-3350 4025) $PN 56
J 0
(-3340 4035);
DISPLAY 0.680851 (-3340 4035);
PAINT MONO (-3340 4035);
FORCEPROP 0 LASTPIN (-3350 4075) $PN 55
J 0
(-3340 4085);
DISPLAY 0.680851 (-3340 4085);
PAINT MONO (-3340 4085);
FORCEPROP 0 LASTPIN (-3350 2975) $PN 238
J 0
(-3340 2985);
DISPLAY 0.680851 (-3340 2985);
PAINT MONO (-3340 2985);
FORCEPROP 0 LASTPIN (-3350 3025) $PN 239
J 0
(-3340 3035);
DISPLAY 0.680851 (-3340 3035);
PAINT MONO (-3340 3035);
FORCEPROP 0 LASTPIN (-3350 4125) $PN 156
J 0
(-3340 4135);
DISPLAY 0.680851 (-3340 4135);
PAINT MONO (-3340 4135);
FORCEPROP 0 LASTPIN (-3350 4175) $PN 157
J 0
(-3340 4185);
DISPLAY 0.680851 (-3340 4185);
PAINT MONO (-3340 4185);
FORCEPROP 0 LASTPIN (-3350 3075) $PN 249
J 0
(-3340 3085);
DISPLAY 0.680851 (-3340 3085);
PAINT MONO (-3340 3085);
FORCEPROP 0 LASTPIN (-3350 3125) $PN 250
J 0
(-3340 3135);
DISPLAY 0.680851 (-3340 3135);
PAINT MONO (-3340 3135);
FORCEPROP 0 LASTPIN (-3350 4225) $PN 167
J 0
(-3340 4235);
DISPLAY 0.680851 (-3340 4235);
PAINT MONO (-3340 4235);
FORCEPROP 0 LASTPIN (-3350 4275) $PN 168
J 0
(-3340 4285);
DISPLAY 0.680851 (-3340 4285);
PAINT MONO (-3340 4285);
FORCEPROP 0 LASTPIN (-3350 3175) $PN 260
J 0
(-3340 3185);
DISPLAY 0.680851 (-3340 3185);
PAINT MONO (-3340 3185);
FORCEPROP 0 LASTPIN (-3350 3225) $PN 261
J 0
(-3340 3235);
DISPLAY 0.680851 (-3340 3235);
PAINT MONO (-3340 3235);
FORCEPROP 0 LASTPIN (-3350 4325) $PN 178
J 0
(-3340 4335);
DISPLAY 0.680851 (-3340 4335);
PAINT MONO (-3340 4335);
FORCEPROP 0 LASTPIN (-3350 4375) $PN 179
J 0
(-3340 4385);
DISPLAY 0.680851 (-3340 4385);
PAINT MONO (-3340 4385);
FORCEPROP 0 LASTPIN (-3350 3275) $PN 271
J 0
(-3340 3285);
DISPLAY 0.680851 (-3340 3285);
PAINT MONO (-3340 3285);
FORCEPROP 0 LASTPIN (-3350 3325) $PN 272
J 0
(-3340 3335);
DISPLAY 0.680851 (-3340 3335);
PAINT MONO (-3340 3335);
FORCEPROP 0 LASTPIN (-3350 4425) $PN 189
J 0
(-3340 4435);
DISPLAY 0.680851 (-3340 4435);
PAINT MONO (-3340 4435);
FORCEPROP 0 LASTPIN (-3350 4475) $PN 190
J 0
(-3340 4485);
DISPLAY 0.680851 (-3340 4485);
PAINT MONO (-3340 4485);
FORCEPROP 0 LASTPIN (-3350 3375) $PN 282
J 0
(-3340 3385);
DISPLAY 0.680851 (-3340 3385);
PAINT MONO (-3340 3385);
FORCEPROP 0 LASTPIN (-3350 3425) $PN 283
J 0
(-3340 3435);
DISPLAY 0.680851 (-3340 3435);
PAINT MONO (-3340 3435);
FORCEPROP 0 LASTPIN (-3350 4525) $PN 200
J 0
(-3340 4535);
DISPLAY 0.680851 (-3340 4535);
PAINT MONO (-3340 4535);
FORCEPROP 0 LASTPIN (-3350 4575) $PN 201
J 0
(-3340 4585);
DISPLAY 0.680851 (-3340 4585);
PAINT MONO (-3340 4585);
FORCEPROP 0 LASTPIN (-3350 3475) $PN 94
J 0
(-3340 3485);
DISPLAY 0.680851 (-3340 3485);
PAINT MONO (-3340 3485);
FORCEPROP 0 LASTPIN (-3350 3525) $PN 93
J 0
(-3340 3535);
DISPLAY 0.680851 (-3340 3535);
PAINT MONO (-3340 3535);
FORCEPROP 2 LAST PART_TYPE SMLF
J 0
(-4550 5000);
DISPLAY 1.021277 (-4550 5000);
FORCEPROP 2 LAST VALUE SCONN288_DDR506112002KQ
J 0
(-4550 4950);
DISPLAY 0.489362 (-4550 4950);
PAINT SKYBLUE (-4550 4950);
FORCEPROP 1 LAST MATERIAL IO
J 0
(-4700 4750);
DISPLAY 0.468085 (-4700 4750);
PAINT SKYBLUE (-4700 4750);
FORCEPROP 1 LAST PART_NUMBER DFHST8FS479
J 0
(-4700 4825);
DISPLAY 0.468085 (-4700 4825);
PAINT SKYBLUE (-4700 4825);
FORCEPROP 1 LAST CDS_LMAN_SYM_OUTLINE -600,1150,600,-1150
J 0
(-4100 3575);
DISPLAY 0.468085 (-4100 3575);
PAINT GREEN (-4100 3575);
DISPLAY INVISIBLE (-4100 3575);
FORCEPROP 1 LAST PATH I236
J 0
(-4100 3575);
DISPLAY 0.723404 (-4100 3575);
PAINT GREEN (-4100 3575);
DISPLAY INVISIBLE (-4100 3575);
FORCEPROP 1 LAST NEEDS_NO_SIZE TRUE
J 0
(-4100 3575);
DISPLAY 0.723404 (-4100 3575);
PAINT GREEN (-4100 3575);
DISPLAY INVISIBLE (-4100 3575);
FORCEPROP 2 LAST CDS_LIB pure_quanta
J 0
(-4100 3575);
DISPLAY INVISIBLE (-4100 3575);
FORCEADD GND..1
(-2675 5525);
FORCEPROP 3 LASTPIN (-2675 5575) SIG_NAME GND\g
J 0
(-2665 5585);
DISPLAY 0.659574 (-2665 5585);
PAINT MONO (-2665 5585);
DISPLAY INVISIBLE (-2665 5585);
FORCEPROP 2 LAST CDS_LIB pure_quanta_power
J 0
(-2675 5525);
DISPLAY INVISIBLE (-2675 5525);
FORCEPROP 2 LAST BOM_COST MEM
J 0
(-2650 5650);
DISPLAY 0.659574 (-2650 5650);
DISPLAY INVISIBLE (-2650 5650);
FORCEPROP 1 LAST SIZE 1B
J 0
(-2600 5475);
DISPLAY 0.723404 (-2600 5475);
PAINT GREEN (-2600 5475);
DISPLAY INVISIBLE (-2600 5475);
FORCEPROP 1 LAST PATH I237
J 0
(-2600 5525);
DISPLAY 0.872340 (-2600 5525);
PAINT AQUA (-2600 5525);
DISPLAY INVISIBLE (-2600 5525);
FORCEPROP 2 LAST ROOM MEM_EFGH_DECOUPLING_CAPS
J 0
(-2650 5600);
DISPLAY 0.659574 (-2650 5600);
PAINT RED (-2650 5600);
DISPLAY INVISIBLE (-2650 5600);
FORCEPROP 1 LAST HDL_POWER GND
J 0
(-2675 5675);
DISPLAY 0.723404 (-2675 5675);
PAINT GREEN (-2675 5675);
DISPLAY INVISIBLE (-2675 5675);
FORCEADD Q_CAP..1
R 2
(-2675 5875);
FORCEPROP 1 LAST LOCATION C157
J 2
(-2725 5975);
DISPLAY 0.489362 (-2725 5975);
PAINT SKYBLUE (-2725 5975);
FORCEPROP 0 LAST $SEC 1
J 0
(-2725 6025);
DISPLAY 0.680851 (-2725 6025);
PAINT MONO (-2725 6025);
DISPLAY INVISIBLE (-2725 6025);
FORCEPROP 0 LAST CDS_SEC 1
J 0
(-2725 6025);
DISPLAY 0.680851 (-2725 6025);
DISPLAY INVISIBLE (-2725 6025);
FORCEPROP 1 LASTPIN (-2675 5975) $PN 1
J 2
(-2685 5955);
DISPLAY 0.489362 (-2685 5955);
PAINT MONO (-2685 5955);
FORCEPROP 1 LASTPIN (-2675 5775) $PN 2
J 2
(-2685 5755);
DISPLAY 0.489362 (-2685 5755);
PAINT MONO (-2685 5755);
FORCEPROP 1 LAST MATERIAL X6S
J 2
(-2725 5775);
DISPLAY 0.489362 (-2725 5775);
PAINT SKYBLUE (-2725 5775);
FORCEPROP 1 LAST TOLERANCE 10%
J 2
(-2725 5825);
DISPLAY 0.489362 (-2725 5825);
PAINT SKYBLUE (-2725 5825);
FORCEPROP 1 LAST VALUE 10UF
J 2
(-2725 5925);
DISPLAY 0.489362 (-2725 5925);
PAINT SKYBLUE (-2725 5925);
FORCEPROP 1 LAST PART_NUMBER CH6104KEA00
J 2
(-2725 5725);
DISPLAY 0.489362 (-2725 5725);
PAINT SKYBLUE (-2725 5725);
FORCEPROP 1 LAST VOLTAGE 25V
J 2
(-2725 5875);
DISPLAY 0.489362 (-2725 5875);
PAINT SKYBLUE (-2725 5875);
FORCEPROP 1 LAST PACK_TYPE C0805
J 2
(-2725 5675);
DISPLAY 0.489362 (-2725 5675);
PAINT SKYBLUE (-2725 5675);
FORCEPROP 0 LAST BOM_COST MEM
J 2
(-2730 6020);
DISPLAY 0.595745 (-2730 6020);
PAINT MONO (-2730 6020);
DISPLAY INVISIBLE (-2730 6020);
FORCEPROP 2 LAST CDS_LIB pure_quanta
J 0
(-2675 5875);
DISPLAY INVISIBLE (-2675 5875);
FORCEPROP 1 LAST PATH I238
J 2
(-2725 6025);
DISPLAY 0.978723 (-2725 6025);
PAINT WHITE (-2725 6025);
DISPLAY INVISIBLE (-2725 6025);
FORCEPROP 0 LAST ROOM MEM_CH_A_CPU0_DIMM1
J 2
(-2730 6020);
DISPLAY 0.595745 (-2730 6020);
PAINT RED (-2730 6020);
DISPLAY INVISIBLE (-2730 6020);
FORCEADD Q_CAP..1
R 2
(-2100 5875);
FORCEPROP 1 LAST LOCATION C158
J 2
(-2150 5975);
DISPLAY 0.489362 (-2150 5975);
PAINT SKYBLUE (-2150 5975);
FORCEPROP 0 LAST $SEC 1
J 0
(-2150 6025);
DISPLAY 0.680851 (-2150 6025);
PAINT MONO (-2150 6025);
DISPLAY INVISIBLE (-2150 6025);
FORCEPROP 0 LAST CDS_SEC 1
J 0
(-2150 6025);
DISPLAY 0.680851 (-2150 6025);
DISPLAY INVISIBLE (-2150 6025);
FORCEPROP 1 LASTPIN (-2100 5975) $PN 1
J 2
(-2110 5955);
DISPLAY 0.489362 (-2110 5955);
PAINT MONO (-2110 5955);
FORCEPROP 1 LASTPIN (-2100 5775) $PN 2
J 2
(-2110 5755);
DISPLAY 0.489362 (-2110 5755);
PAINT MONO (-2110 5755);
FORCEPROP 1 LAST MATERIAL X6S
J 2
(-2150 5775);
DISPLAY 0.489362 (-2150 5775);
PAINT SKYBLUE (-2150 5775);
FORCEPROP 1 LAST TOLERANCE 10%
J 2
(-2150 5825);
DISPLAY 0.489362 (-2150 5825);
PAINT SKYBLUE (-2150 5825);
FORCEPROP 1 LAST VALUE 10UF
J 2
(-2150 5925);
DISPLAY 0.489362 (-2150 5925);
PAINT SKYBLUE (-2150 5925);
FORCEPROP 1 LAST VOLTAGE 25V
J 2
(-2150 5875);
DISPLAY 0.489362 (-2150 5875);
PAINT SKYBLUE (-2150 5875);
FORCEPROP 1 LAST PACK_TYPE C0805
J 2
(-2150 5675);
DISPLAY 0.489362 (-2150 5675);
PAINT SKYBLUE (-2150 5675);
FORCEPROP 1 LAST PART_NUMBER CH6104KEA00
J 2
(-2150 5725);
DISPLAY 0.489362 (-2150 5725);
PAINT SKYBLUE (-2150 5725);
FORCEPROP 0 LAST BOM_COST MEM
J 2
(-2155 6020);
DISPLAY 0.595745 (-2155 6020);
PAINT MONO (-2155 6020);
DISPLAY INVISIBLE (-2155 6020);
FORCEPROP 2 LAST CDS_LIB pure_quanta
J 0
(-2100 5875);
DISPLAY INVISIBLE (-2100 5875);
FORCEPROP 1 LAST PATH I239
J 2
(-2150 6025);
DISPLAY 0.978723 (-2150 6025);
PAINT WHITE (-2150 6025);
DISPLAY INVISIBLE (-2150 6025);
FORCEPROP 0 LAST ROOM MEM_CH_A_CPU0_DIMM1
J 2
(-2155 6020);
DISPLAY 0.595745 (-2155 6020);
PAINT RED (-2155 6020);
DISPLAY INVISIBLE (-2155 6020);
FORCEADD TAP..1
R 2
(-7325 3250);
FORCEPROP 3 LASTPIN (-7275 3250) SIG_NAME M_G_CPU0_SB_CB<1>
J 0
(-7265 3260);
DISPLAY 0.659574 (-7265 3260);
PAINT MONO (-7265 3260);
DISPLAY INVISIBLE (-7265 3260);
FORCEPROP 1 LASTPIN (-7275 3250) BN 1
J 2
(-7263 3258);
DISPLAY 0.489362 (-7263 3258);
PAINT GREEN (-7263 3258);
FORCEPROP 2 LAST CDS_LIB mstr_standard
J 0
(-7325 3250);
DISPLAY 0.723404 (-7325 3250);
PAINT MONO (-7325 3250);
DISPLAY INVISIBLE (-7325 3250);
FORCEPROP 1 LAST BODY_TYPE PLUMBING
J 2
(-7325 3300);
DISPLAY 0.872340 (-7325 3300);
PAINT GREEN (-7325 3300);
DISPLAY INVISIBLE (-7325 3300);
FORCEPROP 1 LAST HDL_TAP TRUE
J 2
(-7650 3125);
DISPLAY 0.872340 (-7650 3125);
DISPLAY INVISIBLE (-7650 3125);
FORCEPROP 1 LAST PATH I24
J 2
(-7323 3250);
DISPLAY 0.872340 (-7323 3250);
PAINT GREEN (-7323 3250);
DISPLAY INVISIBLE (-7323 3250);
FORCEADD UNIVERSAL_POWER..1
(-2675 6200);
FORCEPROP 3 LASTPIN (-2675 6150) SIG_NAME P12V_MEM_0\g
J 0
(-2665 6160);
DISPLAY 0.659574 (-2665 6160);
PAINT MONO (-2665 6160);
DISPLAY INVISIBLE (-2665 6160);
FORCEPROP 1 LAST HDL_POWER P12V_MEM_0
J 1
(-2700 6250);
DISPLAY 0.489362 (-2700 6250);
PAINT GREEN (-2700 6250);
FORCEPROP 2 LAST CDS_LIB pure_quanta_power
J 0
(-2675 6200);
DISPLAY INVISIBLE (-2675 6200);
FORCEPROP 2 LAST BOM_COST VR_SYSTEM
J 0
(-2675 6300);
DISPLAY 0.617021 (-2675 6300);
PAINT PURPLE (-2675 6300);
DISPLAY INVISIBLE (-2675 6300);
FORCEPROP 1 LAST PATH I240
J 0
(-2625 6225);
DISPLAY 0.872340 (-2625 6225);
PAINT AQUA (-2625 6225);
DISPLAY INVISIBLE (-2625 6225);
FORCEADD OFFPAGE..1
(-7925 2700);
FORCEPROP 2 LAST $XR5 96 
J 0
(-8657 2700);
DISPLAY 0.638298 (-8657 2700);
PAINT MONO (-8657 2700);
FORCEPROP 2 LAST $XR4 95 
J 0
(-8567 2700);
DISPLAY 0.638298 (-8567 2700);
PAINT MONO (-8567 2700);
FORCEPROP 2 LAST $XR3 94 
J 0
(-8477 2700);
DISPLAY 0.638298 (-8477 2700);
PAINT MONO (-8477 2700);
FORCEPROP 2 LAST $XR2 93 
J 0
(-8387 2700);
DISPLAY 0.638298 (-8387 2700);
PAINT MONO (-8387 2700);
FORCEPROP 2 LAST $XR1 92 
J 0
(-8297 2700);
DISPLAY 0.638298 (-8297 2700);
PAINT MONO (-8297 2700);
FORCEPROP 2 LAST $XR0 136 
J 0
(-8207 2700);
DISPLAY 0.638298 (-8207 2700);
PAINT MONO (-8207 2700);
FORCEPROP 2 LAST PATH I241
J 0
(-8200 2750);
DISPLAY 0.680851 (-8200 2750);
DISPLAY INVISIBLE (-8200 2750);
FORCEPROP 1 LAST COMMENT_BODY TRUE
J 0
(-7800 2600);
DISPLAY 0.872340 (-7800 2600);
PAINT GREEN (-7800 2600);
DISPLAY INVISIBLE (-7800 2600);
FORCEPROP 1 LAST OFFPAGE TRUE
J 0
(-7600 2575);
DISPLAY 0.872340 (-7600 2575);
PAINT GREEN (-7600 2575);
DISPLAY INVISIBLE (-7600 2575);
FORCEPROP 2 LAST CDS_LIB mstr_standard
J 0
(-7925 2700);
DISPLAY 0.808511 (-7925 2700);
DISPLAY INVISIBLE (-7925 2700);
FORCEADD Q_RES..1
(-7375 2700);
FORCEPROP 1 LAST $LOCATION R1574
J 0
(-7425 2725);
DISPLAY 0.510638 (-7425 2725);
PAINT SKYBLUE (-7425 2725);
FORCEPROP 0 LAST CDS_LOCATION R1574
J 0
(-7425 2800);
DISPLAY 0.680851 (-7425 2800);
DISPLAY INVISIBLE (-7425 2800);
FORCEPROP 0 LAST $SEC 1
J 0
(-7425 2800);
DISPLAY 0.680851 (-7425 2800);
PAINT MONO (-7425 2800);
DISPLAY INVISIBLE (-7425 2800);
FORCEPROP 0 LAST CDS_SEC 1
J 0
(-7425 2800);
DISPLAY 0.680851 (-7425 2800);
DISPLAY INVISIBLE (-7425 2800);
FORCEPROP 1 LASTPIN (-7475 2700) $PN 1
J 0
(-7463 2712);
DISPLAY 0.787234 (-7463 2712);
PAINT MONO (-7463 2712);
FORCEPROP 1 LASTPIN (-7275 2700) $PN 2
J 0
(-7313 2712);
DISPLAY 0.787234 (-7313 2712);
PAINT MONO (-7313 2712);
FORCEPROP 1 LAST VALUE 49.9
J 2
(-7225 2775);
DISPLAY 0.510638 (-7225 2775);
PAINT SKYBLUE (-7225 2775);
FORCEPROP 2 LAST CDS_LIB pure_quanta
J 0
(-7375 2700);
DISPLAY INVISIBLE (-7375 2700);
FORCEPROP 1 LAST PATH I242
J 0
(-7425 2850);
DISPLAY 0.978723 (-7425 2850);
PAINT WHITE (-7425 2850);
DISPLAY INVISIBLE (-7425 2850);
FORCEPROP 1 LAST MATERIAL CHIP
J 0
(-7375 2550);
DISPLAY 0.978723 (-7375 2550);
DISPLAY INVISIBLE (-7375 2550);
FORCEPROP 1 LAST PACK_TYPE 0402LF
J 0
(-7125 2550);
DISPLAY 0.978723 (-7125 2550);
DISPLAY INVISIBLE (-7125 2550);
FORCEPROP 1 LAST WATTAGE 1/16W
J 2
(-7400 2550);
DISPLAY 0.978723 (-7400 2550);
DISPLAY INVISIBLE (-7400 2550);
FORCEPROP 1 LAST TOLERANCE 1%
J 0
(-7375 2600);
DISPLAY 0.978723 (-7375 2600);
DISPLAY INVISIBLE (-7375 2600);
FORCEPROP 1 LAST PART_NUMBER CS04992FB07
J 0
(-7425 2800);
DISPLAY 0.978723 (-7425 2800);
DISPLAY INVISIBLE (-7425 2800);
FORCEADD TAP..1
R 2
(-7325 3300);
FORCEPROP 3 LASTPIN (-7275 3300) SIG_NAME M_G_CPU0_SB_CB<2>
J 0
(-7265 3310);
DISPLAY 0.659574 (-7265 3310);
PAINT MONO (-7265 3310);
DISPLAY INVISIBLE (-7265 3310);
FORCEPROP 1 LASTPIN (-7275 3300) BN 2
J 2
(-7263 3308);
DISPLAY 0.489362 (-7263 3308);
PAINT GREEN (-7263 3308);
FORCEPROP 2 LAST CDS_LIB mstr_standard
J 0
(-7325 3300);
DISPLAY 0.723404 (-7325 3300);
PAINT MONO (-7325 3300);
DISPLAY INVISIBLE (-7325 3300);
FORCEPROP 1 LAST BODY_TYPE PLUMBING
J 2
(-7325 3350);
DISPLAY 0.872340 (-7325 3350);
PAINT GREEN (-7325 3350);
DISPLAY INVISIBLE (-7325 3350);
FORCEPROP 1 LAST HDL_TAP TRUE
J 2
(-7650 3175);
DISPLAY 0.872340 (-7650 3175);
DISPLAY INVISIBLE (-7650 3175);
FORCEPROP 1 LAST PATH I25
J 2
(-7323 3300);
DISPLAY 0.872340 (-7323 3300);
PAINT GREEN (-7323 3300);
DISPLAY INVISIBLE (-7323 3300);
FORCEADD TAP..1
R 2
(-7325 3350);
FORCEPROP 3 LASTPIN (-7275 3350) SIG_NAME M_G_CPU0_SB_CB<3>
J 0
(-7265 3360);
DISPLAY 0.659574 (-7265 3360);
PAINT MONO (-7265 3360);
DISPLAY INVISIBLE (-7265 3360);
FORCEPROP 1 LASTPIN (-7275 3350) BN 3
J 2
(-7263 3358);
DISPLAY 0.489362 (-7263 3358);
PAINT GREEN (-7263 3358);
FORCEPROP 2 LAST CDS_LIB mstr_standard
J 0
(-7325 3350);
DISPLAY 0.723404 (-7325 3350);
PAINT MONO (-7325 3350);
DISPLAY INVISIBLE (-7325 3350);
FORCEPROP 1 LAST BODY_TYPE PLUMBING
J 2
(-7325 3400);
DISPLAY 0.872340 (-7325 3400);
PAINT GREEN (-7325 3400);
DISPLAY INVISIBLE (-7325 3400);
FORCEPROP 1 LAST HDL_TAP TRUE
J 2
(-7650 3225);
DISPLAY 0.872340 (-7650 3225);
DISPLAY INVISIBLE (-7650 3225);
FORCEPROP 1 LAST PATH I26
J 2
(-7323 3350);
DISPLAY 0.872340 (-7323 3350);
PAINT GREEN (-7323 3350);
DISPLAY INVISIBLE (-7323 3350);
FORCEADD TAP..1
R 2
(-7325 3400);
FORCEPROP 3 LASTPIN (-7275 3400) SIG_NAME M_G_CPU0_SB_CB<4>
J 0
(-7265 3410);
DISPLAY 0.659574 (-7265 3410);
PAINT MONO (-7265 3410);
DISPLAY INVISIBLE (-7265 3410);
FORCEPROP 1 LASTPIN (-7275 3400) BN 4
J 2
(-7263 3408);
DISPLAY 0.489362 (-7263 3408);
PAINT GREEN (-7263 3408);
FORCEPROP 2 LAST CDS_LIB mstr_standard
J 0
(-7325 3400);
DISPLAY 0.723404 (-7325 3400);
PAINT MONO (-7325 3400);
DISPLAY INVISIBLE (-7325 3400);
FORCEPROP 1 LAST BODY_TYPE PLUMBING
J 2
(-7325 3450);
DISPLAY 0.872340 (-7325 3450);
PAINT GREEN (-7325 3450);
DISPLAY INVISIBLE (-7325 3450);
FORCEPROP 1 LAST HDL_TAP TRUE
J 2
(-7650 3275);
DISPLAY 0.872340 (-7650 3275);
DISPLAY INVISIBLE (-7650 3275);
FORCEPROP 1 LAST PATH I27
J 2
(-7323 3400);
DISPLAY 0.872340 (-7323 3400);
PAINT GREEN (-7323 3400);
DISPLAY INVISIBLE (-7323 3400);
FORCEADD TAP..1
R 2
(-7325 3450);
FORCEPROP 3 LASTPIN (-7275 3450) SIG_NAME M_G_CPU0_SB_CB<5>
J 0
(-7265 3460);
DISPLAY 0.659574 (-7265 3460);
PAINT MONO (-7265 3460);
DISPLAY INVISIBLE (-7265 3460);
FORCEPROP 1 LASTPIN (-7275 3450) BN 5
J 2
(-7263 3458);
DISPLAY 0.489362 (-7263 3458);
PAINT GREEN (-7263 3458);
FORCEPROP 2 LAST CDS_LIB mstr_standard
J 0
(-7325 3450);
DISPLAY 0.723404 (-7325 3450);
PAINT MONO (-7325 3450);
DISPLAY INVISIBLE (-7325 3450);
FORCEPROP 1 LAST BODY_TYPE PLUMBING
J 2
(-7325 3500);
DISPLAY 0.872340 (-7325 3500);
PAINT GREEN (-7325 3500);
DISPLAY INVISIBLE (-7325 3500);
FORCEPROP 1 LAST HDL_TAP TRUE
J 2
(-7650 3325);
DISPLAY 0.872340 (-7650 3325);
DISPLAY INVISIBLE (-7650 3325);
FORCEPROP 1 LAST PATH I28
J 2
(-7323 3450);
DISPLAY 0.872340 (-7323 3450);
PAINT GREEN (-7323 3450);
DISPLAY INVISIBLE (-7323 3450);
FORCEADD TAP..1
R 2
(-7325 3500);
FORCEPROP 3 LASTPIN (-7275 3500) SIG_NAME M_G_CPU0_SB_CB<6>
J 0
(-7265 3510);
DISPLAY 0.659574 (-7265 3510);
PAINT MONO (-7265 3510);
DISPLAY INVISIBLE (-7265 3510);
FORCEPROP 1 LASTPIN (-7275 3500) BN 6
J 2
(-7263 3508);
DISPLAY 0.489362 (-7263 3508);
PAINT GREEN (-7263 3508);
FORCEPROP 2 LAST CDS_LIB mstr_standard
J 0
(-7325 3500);
DISPLAY 0.723404 (-7325 3500);
PAINT MONO (-7325 3500);
DISPLAY INVISIBLE (-7325 3500);
FORCEPROP 1 LAST BODY_TYPE PLUMBING
J 2
(-7325 3550);
DISPLAY 0.872340 (-7325 3550);
PAINT GREEN (-7325 3550);
DISPLAY INVISIBLE (-7325 3550);
FORCEPROP 1 LAST HDL_TAP TRUE
J 2
(-7650 3375);
DISPLAY 0.872340 (-7650 3375);
DISPLAY INVISIBLE (-7650 3375);
FORCEPROP 1 LAST PATH I29
J 2
(-7323 3500);
DISPLAY 0.872340 (-7323 3500);
PAINT GREEN (-7323 3500);
DISPLAY INVISIBLE (-7323 3500);
FORCEADD TAP..1
R 2
(-7325 3550);
FORCEPROP 3 LASTPIN (-7275 3550) SIG_NAME M_G_CPU0_SB_CB<7>
J 0
(-7265 3560);
DISPLAY 0.659574 (-7265 3560);
PAINT MONO (-7265 3560);
DISPLAY INVISIBLE (-7265 3560);
FORCEPROP 1 LASTPIN (-7275 3550) BN 7
J 2
(-7263 3558);
DISPLAY 0.489362 (-7263 3558);
PAINT GREEN (-7263 3558);
FORCEPROP 2 LAST CDS_LIB mstr_standard
J 0
(-7325 3550);
DISPLAY 0.723404 (-7325 3550);
PAINT MONO (-7325 3550);
DISPLAY INVISIBLE (-7325 3550);
FORCEPROP 1 LAST BODY_TYPE PLUMBING
J 2
(-7325 3600);
DISPLAY 0.872340 (-7325 3600);
PAINT GREEN (-7325 3600);
DISPLAY INVISIBLE (-7325 3600);
FORCEPROP 1 LAST HDL_TAP TRUE
J 2
(-7650 3425);
DISPLAY 0.872340 (-7650 3425);
DISPLAY INVISIBLE (-7650 3425);
FORCEPROP 1 LAST PATH I30
J 2
(-7323 3550);
DISPLAY 0.872340 (-7323 3550);
PAINT GREEN (-7323 3550);
DISPLAY INVISIBLE (-7323 3550);
FORCEADD TAP..1
R 2
(-7325 3650);
FORCEPROP 3 LASTPIN (-7275 3650) SIG_NAME M_G_CPU0_SA_CB<0>
J 0
(-7265 3660);
DISPLAY 0.659574 (-7265 3660);
PAINT MONO (-7265 3660);
DISPLAY INVISIBLE (-7265 3660);
FORCEPROP 1 LASTPIN (-7275 3650) BN 0
J 2
(-7263 3658);
DISPLAY 0.489362 (-7263 3658);
PAINT GREEN (-7263 3658);
FORCEPROP 2 LAST CDS_LIB mstr_standard
J 0
(-7325 3650);
DISPLAY 0.723404 (-7325 3650);
PAINT MONO (-7325 3650);
DISPLAY INVISIBLE (-7325 3650);
FORCEPROP 1 LAST BODY_TYPE PLUMBING
J 2
(-7325 3700);
DISPLAY 0.872340 (-7325 3700);
PAINT GREEN (-7325 3700);
DISPLAY INVISIBLE (-7325 3700);
FORCEPROP 1 LAST HDL_TAP TRUE
J 2
(-7650 3525);
DISPLAY 0.872340 (-7650 3525);
DISPLAY INVISIBLE (-7650 3525);
FORCEPROP 1 LAST PATH I31
J 2
(-7323 3650);
DISPLAY 0.872340 (-7323 3650);
PAINT GREEN (-7323 3650);
DISPLAY INVISIBLE (-7323 3650);
FORCEADD TAP..1
R 2
(-7325 3700);
FORCEPROP 3 LASTPIN (-7275 3700) SIG_NAME M_G_CPU0_SA_CB<1>
J 0
(-7265 3710);
DISPLAY 0.659574 (-7265 3710);
PAINT MONO (-7265 3710);
DISPLAY INVISIBLE (-7265 3710);
FORCEPROP 1 LASTPIN (-7275 3700) BN 1
J 2
(-7263 3708);
DISPLAY 0.489362 (-7263 3708);
PAINT GREEN (-7263 3708);
FORCEPROP 2 LAST CDS_LIB mstr_standard
J 0
(-7325 3700);
DISPLAY 0.723404 (-7325 3700);
PAINT MONO (-7325 3700);
DISPLAY INVISIBLE (-7325 3700);
FORCEPROP 1 LAST BODY_TYPE PLUMBING
J 2
(-7325 3750);
DISPLAY 0.872340 (-7325 3750);
PAINT GREEN (-7325 3750);
DISPLAY INVISIBLE (-7325 3750);
FORCEPROP 1 LAST HDL_TAP TRUE
J 2
(-7650 3575);
DISPLAY 0.872340 (-7650 3575);
DISPLAY INVISIBLE (-7650 3575);
FORCEPROP 1 LAST PATH I32
J 2
(-7323 3700);
DISPLAY 0.872340 (-7323 3700);
PAINT GREEN (-7323 3700);
DISPLAY INVISIBLE (-7323 3700);
FORCEADD TAP..1
R 2
(-7325 3750);
FORCEPROP 3 LASTPIN (-7275 3750) SIG_NAME M_G_CPU0_SA_CB<2>
J 0
(-7265 3760);
DISPLAY 0.659574 (-7265 3760);
PAINT MONO (-7265 3760);
DISPLAY INVISIBLE (-7265 3760);
FORCEPROP 1 LASTPIN (-7275 3750) BN 2
J 2
(-7263 3758);
DISPLAY 0.489362 (-7263 3758);
PAINT GREEN (-7263 3758);
FORCEPROP 2 LAST CDS_LIB mstr_standard
J 0
(-7325 3750);
DISPLAY 0.723404 (-7325 3750);
PAINT MONO (-7325 3750);
DISPLAY INVISIBLE (-7325 3750);
FORCEPROP 1 LAST BODY_TYPE PLUMBING
J 2
(-7325 3800);
DISPLAY 0.872340 (-7325 3800);
PAINT GREEN (-7325 3800);
DISPLAY INVISIBLE (-7325 3800);
FORCEPROP 1 LAST HDL_TAP TRUE
J 2
(-7650 3625);
DISPLAY 0.872340 (-7650 3625);
DISPLAY INVISIBLE (-7650 3625);
FORCEPROP 1 LAST PATH I33
J 2
(-7323 3750);
DISPLAY 0.872340 (-7323 3750);
PAINT GREEN (-7323 3750);
DISPLAY INVISIBLE (-7323 3750);
FORCEADD TAP..1
R 2
(-7325 3800);
FORCEPROP 3 LASTPIN (-7275 3800) SIG_NAME M_G_CPU0_SA_CB<3>
J 0
(-7265 3810);
DISPLAY 0.659574 (-7265 3810);
PAINT MONO (-7265 3810);
DISPLAY INVISIBLE (-7265 3810);
FORCEPROP 1 LASTPIN (-7275 3800) BN 3
J 2
(-7263 3808);
DISPLAY 0.489362 (-7263 3808);
PAINT GREEN (-7263 3808);
FORCEPROP 2 LAST CDS_LIB mstr_standard
J 0
(-7325 3800);
DISPLAY 0.723404 (-7325 3800);
PAINT MONO (-7325 3800);
DISPLAY INVISIBLE (-7325 3800);
FORCEPROP 1 LAST BODY_TYPE PLUMBING
J 2
(-7325 3850);
DISPLAY 0.872340 (-7325 3850);
PAINT GREEN (-7325 3850);
DISPLAY INVISIBLE (-7325 3850);
FORCEPROP 1 LAST HDL_TAP TRUE
J 2
(-7650 3675);
DISPLAY 0.872340 (-7650 3675);
DISPLAY INVISIBLE (-7650 3675);
FORCEPROP 1 LAST PATH I34
J 2
(-7323 3800);
DISPLAY 0.872340 (-7323 3800);
PAINT GREEN (-7323 3800);
DISPLAY INVISIBLE (-7323 3800);
FORCEADD TAP..1
R 2
(-7325 3850);
FORCEPROP 3 LASTPIN (-7275 3850) SIG_NAME M_G_CPU0_SA_CB<4>
J 0
(-7265 3860);
DISPLAY 0.659574 (-7265 3860);
PAINT MONO (-7265 3860);
DISPLAY INVISIBLE (-7265 3860);
FORCEPROP 1 LASTPIN (-7275 3850) BN 4
J 2
(-7263 3858);
DISPLAY 0.489362 (-7263 3858);
PAINT GREEN (-7263 3858);
FORCEPROP 2 LAST CDS_LIB mstr_standard
J 0
(-7325 3850);
DISPLAY 0.723404 (-7325 3850);
PAINT MONO (-7325 3850);
DISPLAY INVISIBLE (-7325 3850);
FORCEPROP 1 LAST BODY_TYPE PLUMBING
J 2
(-7325 3900);
DISPLAY 0.872340 (-7325 3900);
PAINT GREEN (-7325 3900);
DISPLAY INVISIBLE (-7325 3900);
FORCEPROP 1 LAST HDL_TAP TRUE
J 2
(-7650 3725);
DISPLAY 0.872340 (-7650 3725);
DISPLAY INVISIBLE (-7650 3725);
FORCEPROP 1 LAST PATH I35
J 2
(-7323 3850);
DISPLAY 0.872340 (-7323 3850);
PAINT GREEN (-7323 3850);
DISPLAY INVISIBLE (-7323 3850);
FORCEADD TAP..1
R 2
(-7325 3900);
FORCEPROP 3 LASTPIN (-7275 3900) SIG_NAME M_G_CPU0_SA_CB<5>
J 0
(-7265 3910);
DISPLAY 0.659574 (-7265 3910);
PAINT MONO (-7265 3910);
DISPLAY INVISIBLE (-7265 3910);
FORCEPROP 1 LASTPIN (-7275 3900) BN 5
J 2
(-7263 3908);
DISPLAY 0.489362 (-7263 3908);
PAINT GREEN (-7263 3908);
FORCEPROP 2 LAST CDS_LIB mstr_standard
J 0
(-7325 3900);
DISPLAY 0.723404 (-7325 3900);
PAINT MONO (-7325 3900);
DISPLAY INVISIBLE (-7325 3900);
FORCEPROP 1 LAST BODY_TYPE PLUMBING
J 2
(-7325 3950);
DISPLAY 0.872340 (-7325 3950);
PAINT GREEN (-7325 3950);
DISPLAY INVISIBLE (-7325 3950);
FORCEPROP 1 LAST HDL_TAP TRUE
J 2
(-7650 3775);
DISPLAY 0.872340 (-7650 3775);
DISPLAY INVISIBLE (-7650 3775);
FORCEPROP 1 LAST PATH I36
J 2
(-7323 3900);
DISPLAY 0.872340 (-7323 3900);
PAINT GREEN (-7323 3900);
DISPLAY INVISIBLE (-7323 3900);
FORCEADD TAP..1
R 2
(-7325 3950);
FORCEPROP 3 LASTPIN (-7275 3950) SIG_NAME M_G_CPU0_SA_CB<6>
J 0
(-7265 3960);
DISPLAY 0.659574 (-7265 3960);
PAINT MONO (-7265 3960);
DISPLAY INVISIBLE (-7265 3960);
FORCEPROP 1 LASTPIN (-7275 3950) BN 6
J 2
(-7263 3958);
DISPLAY 0.489362 (-7263 3958);
PAINT GREEN (-7263 3958);
FORCEPROP 2 LAST CDS_LIB mstr_standard
J 0
(-7325 3950);
DISPLAY 0.723404 (-7325 3950);
PAINT MONO (-7325 3950);
DISPLAY INVISIBLE (-7325 3950);
FORCEPROP 1 LAST BODY_TYPE PLUMBING
J 2
(-7325 4000);
DISPLAY 0.872340 (-7325 4000);
PAINT GREEN (-7325 4000);
DISPLAY INVISIBLE (-7325 4000);
FORCEPROP 1 LAST HDL_TAP TRUE
J 2
(-7650 3825);
DISPLAY 0.872340 (-7650 3825);
DISPLAY INVISIBLE (-7650 3825);
FORCEPROP 1 LAST PATH I37
J 2
(-7323 3950);
DISPLAY 0.872340 (-7323 3950);
PAINT GREEN (-7323 3950);
DISPLAY INVISIBLE (-7323 3950);
FORCEADD TAP..1
R 2
(-7325 4000);
FORCEPROP 3 LASTPIN (-7275 4000) SIG_NAME M_G_CPU0_SA_CB<7>
J 0
(-7265 4010);
DISPLAY 0.659574 (-7265 4010);
PAINT MONO (-7265 4010);
DISPLAY INVISIBLE (-7265 4010);
FORCEPROP 1 LASTPIN (-7275 4000) BN 7
J 2
(-7263 4008);
DISPLAY 0.489362 (-7263 4008);
PAINT GREEN (-7263 4008);
FORCEPROP 2 LAST CDS_LIB mstr_standard
J 0
(-7325 4000);
DISPLAY 0.723404 (-7325 4000);
PAINT MONO (-7325 4000);
DISPLAY INVISIBLE (-7325 4000);
FORCEPROP 1 LAST BODY_TYPE PLUMBING
J 2
(-7325 4050);
DISPLAY 0.872340 (-7325 4050);
PAINT GREEN (-7325 4050);
DISPLAY INVISIBLE (-7325 4050);
FORCEPROP 1 LAST HDL_TAP TRUE
J 2
(-7650 3875);
DISPLAY 0.872340 (-7650 3875);
DISPLAY INVISIBLE (-7650 3875);
FORCEPROP 1 LAST PATH I38
J 2
(-7323 4000);
DISPLAY 0.872340 (-7323 4000);
PAINT GREEN (-7323 4000);
DISPLAY INVISIBLE (-7323 4000);
FORCEADD TAP..1
(-5625 2250);
FORCEPROP 3 LASTPIN (-5675 2250) SIG_NAME M_G_CPU0_SB_DQ<1>
J 0
(-5665 2260);
DISPLAY 0.659574 (-5665 2260);
PAINT MONO (-5665 2260);
DISPLAY INVISIBLE (-5665 2260);
FORCEPROP 1 LASTPIN (-5675 2250) BN 1
J 0
(-5687 2258);
DISPLAY 0.489362 (-5687 2258);
PAINT GREEN (-5687 2258);
FORCEPROP 2 LAST CDS_LIB mstr_standard
J 0
(-5625 2250);
DISPLAY 0.723404 (-5625 2250);
PAINT MONO (-5625 2250);
DISPLAY INVISIBLE (-5625 2250);
FORCEPROP 1 LAST BODY_TYPE PLUMBING
J 0
(-5625 2300);
DISPLAY 0.872340 (-5625 2300);
PAINT GREEN (-5625 2300);
DISPLAY INVISIBLE (-5625 2300);
FORCEPROP 1 LAST HDL_TAP TRUE
J 0
(-5300 2125);
DISPLAY 0.872340 (-5300 2125);
DISPLAY INVISIBLE (-5300 2125);
FORCEPROP 1 LAST PATH I46
J 0
(-5627 2250);
DISPLAY 0.872340 (-5627 2250);
PAINT GREEN (-5627 2250);
DISPLAY INVISIBLE (-5627 2250);
FORCEADD TAP..1
(-5625 2200);
FORCEPROP 3 LASTPIN (-5675 2200) SIG_NAME M_G_CPU0_SB_DQ<0>
J 0
(-5665 2210);
DISPLAY 0.659574 (-5665 2210);
PAINT MONO (-5665 2210);
DISPLAY INVISIBLE (-5665 2210);
FORCEPROP 1 LASTPIN (-5675 2200) BN 0
J 0
(-5687 2208);
DISPLAY 0.489362 (-5687 2208);
PAINT GREEN (-5687 2208);
FORCEPROP 2 LAST CDS_LIB mstr_standard
J 0
(-5625 2200);
DISPLAY 0.723404 (-5625 2200);
PAINT MONO (-5625 2200);
DISPLAY INVISIBLE (-5625 2200);
FORCEPROP 1 LAST BODY_TYPE PLUMBING
J 0
(-5625 2250);
DISPLAY 0.872340 (-5625 2250);
PAINT GREEN (-5625 2250);
DISPLAY INVISIBLE (-5625 2250);
FORCEPROP 1 LAST HDL_TAP TRUE
J 0
(-5300 2075);
DISPLAY 0.872340 (-5300 2075);
DISPLAY INVISIBLE (-5300 2075);
FORCEPROP 1 LAST PATH I47
J 0
(-5627 2200);
DISPLAY 0.872340 (-5627 2200);
PAINT GREEN (-5627 2200);
DISPLAY INVISIBLE (-5627 2200);
FORCEADD TAP..1
(-5625 2400);
FORCEPROP 3 LASTPIN (-5675 2400) SIG_NAME M_G_CPU0_SB_DQ<4>
J 0
(-5665 2410);
DISPLAY 0.659574 (-5665 2410);
PAINT MONO (-5665 2410);
DISPLAY INVISIBLE (-5665 2410);
FORCEPROP 1 LASTPIN (-5675 2400) BN 4
J 0
(-5687 2408);
DISPLAY 0.489362 (-5687 2408);
PAINT GREEN (-5687 2408);
FORCEPROP 2 LAST CDS_LIB mstr_standard
J 0
(-5625 2400);
DISPLAY 0.723404 (-5625 2400);
PAINT MONO (-5625 2400);
DISPLAY INVISIBLE (-5625 2400);
FORCEPROP 1 LAST BODY_TYPE PLUMBING
J 0
(-5625 2450);
DISPLAY 0.872340 (-5625 2450);
PAINT GREEN (-5625 2450);
DISPLAY INVISIBLE (-5625 2450);
FORCEPROP 1 LAST HDL_TAP TRUE
J 0
(-5300 2275);
DISPLAY 0.872340 (-5300 2275);
DISPLAY INVISIBLE (-5300 2275);
FORCEPROP 1 LAST PATH I48
J 0
(-5627 2400);
DISPLAY 0.872340 (-5627 2400);
PAINT GREEN (-5627 2400);
DISPLAY INVISIBLE (-5627 2400);
FORCEADD TAP..1
(-5625 2350);
FORCEPROP 3 LASTPIN (-5675 2350) SIG_NAME M_G_CPU0_SB_DQ<3>
J 0
(-5665 2360);
DISPLAY 0.659574 (-5665 2360);
PAINT MONO (-5665 2360);
DISPLAY INVISIBLE (-5665 2360);
FORCEPROP 1 LASTPIN (-5675 2350) BN 3
J 0
(-5687 2358);
DISPLAY 0.489362 (-5687 2358);
PAINT GREEN (-5687 2358);
FORCEPROP 2 LAST CDS_LIB mstr_standard
J 0
(-5625 2350);
DISPLAY 0.723404 (-5625 2350);
PAINT MONO (-5625 2350);
DISPLAY INVISIBLE (-5625 2350);
FORCEPROP 1 LAST BODY_TYPE PLUMBING
J 0
(-5625 2400);
DISPLAY 0.872340 (-5625 2400);
PAINT GREEN (-5625 2400);
DISPLAY INVISIBLE (-5625 2400);
FORCEPROP 1 LAST HDL_TAP TRUE
J 0
(-5300 2225);
DISPLAY 0.872340 (-5300 2225);
DISPLAY INVISIBLE (-5300 2225);
FORCEPROP 1 LAST PATH I49
J 0
(-5627 2350);
DISPLAY 0.872340 (-5627 2350);
PAINT GREEN (-5627 2350);
DISPLAY INVISIBLE (-5627 2350);
FORCEADD OFFPAGE..6
(-7925 2850);
FORCEPROP 2 LAST $XR5 136 
J 0
(-8684 2850);
DISPLAY 0.638298 (-8684 2850);
PAINT MONO (-8684 2850);
FORCEPROP 2 LAST $XR4 96 
J 0
(-8564 2850);
DISPLAY 0.638298 (-8564 2850);
PAINT MONO (-8564 2850);
FORCEPROP 2 LAST $XR3 95 
J 0
(-8474 2850);
DISPLAY 0.638298 (-8474 2850);
PAINT MONO (-8474 2850);
FORCEPROP 2 LAST $XR2 94 
J 0
(-8384 2850);
DISPLAY 0.638298 (-8384 2850);
PAINT MONO (-8384 2850);
FORCEPROP 2 LAST $XR1 93 
J 0
(-8294 2850);
DISPLAY 0.638298 (-8294 2850);
PAINT MONO (-8294 2850);
FORCEPROP 2 LAST $XR0 92 
J 0
(-8204 2850);
DISPLAY 0.638298 (-8204 2850);
PAINT MONO (-8204 2850);
FORCEPROP 2 LAST PATH I5
J 0
(-8200 2900);
DISPLAY 1.021277 (-8200 2900);
DISPLAY INVISIBLE (-8200 2900);
FORCEPROP 1 LAST COMMENT_BODY TRUE
J 0
(-7825 2775);
DISPLAY 0.872340 (-7825 2775);
PAINT GREEN (-7825 2775);
DISPLAY INVISIBLE (-7825 2775);
FORCEPROP 1 LAST OFFPAGE TRUE
J 0
(-7600 2725);
DISPLAY 0.872340 (-7600 2725);
PAINT GREEN (-7600 2725);
DISPLAY INVISIBLE (-7600 2725);
FORCEPROP 2 LAST CDS_LIB mstr_standard
J 0
(-7925 2850);
DISPLAY 0.808511 (-7925 2850);
DISPLAY INVISIBLE (-7925 2850);
FORCEADD TAP..1
(-5625 2300);
FORCEPROP 3 LASTPIN (-5675 2300) SIG_NAME M_G_CPU0_SB_DQ<2>
J 0
(-5665 2310);
DISPLAY 0.659574 (-5665 2310);
PAINT MONO (-5665 2310);
DISPLAY INVISIBLE (-5665 2310);
FORCEPROP 1 LASTPIN (-5675 2300) BN 2
J 0
(-5687 2308);
DISPLAY 0.489362 (-5687 2308);
PAINT GREEN (-5687 2308);
FORCEPROP 2 LAST CDS_LIB mstr_standard
J 0
(-5625 2300);
DISPLAY 0.723404 (-5625 2300);
PAINT MONO (-5625 2300);
DISPLAY INVISIBLE (-5625 2300);
FORCEPROP 1 LAST BODY_TYPE PLUMBING
J 0
(-5625 2350);
DISPLAY 0.872340 (-5625 2350);
PAINT GREEN (-5625 2350);
DISPLAY INVISIBLE (-5625 2350);
FORCEPROP 1 LAST HDL_TAP TRUE
J 0
(-5300 2175);
DISPLAY 0.872340 (-5300 2175);
DISPLAY INVISIBLE (-5300 2175);
FORCEPROP 1 LAST PATH I50
J 0
(-5627 2300);
DISPLAY 0.872340 (-5627 2300);
PAINT GREEN (-5627 2300);
DISPLAY INVISIBLE (-5627 2300);
FORCEADD TAP..1
(-5625 2450);
FORCEPROP 3 LASTPIN (-5675 2450) SIG_NAME M_G_CPU0_SB_DQ<5>
J 0
(-5665 2460);
DISPLAY 0.659574 (-5665 2460);
PAINT MONO (-5665 2460);
DISPLAY INVISIBLE (-5665 2460);
FORCEPROP 1 LASTPIN (-5675 2450) BN 5
J 0
(-5687 2458);
DISPLAY 0.489362 (-5687 2458);
PAINT GREEN (-5687 2458);
FORCEPROP 2 LAST CDS_LIB mstr_standard
J 0
(-5625 2450);
DISPLAY 0.723404 (-5625 2450);
PAINT MONO (-5625 2450);
DISPLAY INVISIBLE (-5625 2450);
FORCEPROP 1 LAST BODY_TYPE PLUMBING
J 0
(-5625 2500);
DISPLAY 0.872340 (-5625 2500);
PAINT GREEN (-5625 2500);
DISPLAY INVISIBLE (-5625 2500);
FORCEPROP 1 LAST HDL_TAP TRUE
J 0
(-5300 2325);
DISPLAY 0.872340 (-5300 2325);
DISPLAY INVISIBLE (-5300 2325);
FORCEPROP 1 LAST PATH I51
J 0
(-5627 2450);
DISPLAY 0.872340 (-5627 2450);
PAINT GREEN (-5627 2450);
DISPLAY INVISIBLE (-5627 2450);
FORCEADD TAP..1
(-5625 2500);
FORCEPROP 3 LASTPIN (-5675 2500) SIG_NAME M_G_CPU0_SB_DQ<6>
J 0
(-5665 2510);
DISPLAY 0.659574 (-5665 2510);
PAINT MONO (-5665 2510);
DISPLAY INVISIBLE (-5665 2510);
FORCEPROP 1 LASTPIN (-5675 2500) BN 6
J 0
(-5687 2508);
DISPLAY 0.489362 (-5687 2508);
PAINT GREEN (-5687 2508);
FORCEPROP 2 LAST CDS_LIB mstr_standard
J 0
(-5625 2500);
DISPLAY 0.723404 (-5625 2500);
PAINT MONO (-5625 2500);
DISPLAY INVISIBLE (-5625 2500);
FORCEPROP 1 LAST BODY_TYPE PLUMBING
J 0
(-5625 2550);
DISPLAY 0.872340 (-5625 2550);
PAINT GREEN (-5625 2550);
DISPLAY INVISIBLE (-5625 2550);
FORCEPROP 1 LAST HDL_TAP TRUE
J 0
(-5300 2375);
DISPLAY 0.872340 (-5300 2375);
DISPLAY INVISIBLE (-5300 2375);
FORCEPROP 1 LAST PATH I52
J 0
(-5627 2500);
DISPLAY 0.872340 (-5627 2500);
PAINT GREEN (-5627 2500);
DISPLAY INVISIBLE (-5627 2500);
FORCEADD TAP..1
(-5625 2650);
FORCEPROP 3 LASTPIN (-5675 2650) SIG_NAME M_G_CPU0_SB_DQ<9>
J 0
(-5665 2660);
DISPLAY 0.659574 (-5665 2660);
PAINT MONO (-5665 2660);
DISPLAY INVISIBLE (-5665 2660);
FORCEPROP 1 LASTPIN (-5675 2650) BN 9
J 0
(-5687 2658);
DISPLAY 0.489362 (-5687 2658);
PAINT GREEN (-5687 2658);
FORCEPROP 2 LAST CDS_LIB mstr_standard
J 0
(-5625 2650);
DISPLAY 0.723404 (-5625 2650);
PAINT MONO (-5625 2650);
DISPLAY INVISIBLE (-5625 2650);
FORCEPROP 1 LAST BODY_TYPE PLUMBING
J 0
(-5625 2700);
DISPLAY 0.872340 (-5625 2700);
PAINT GREEN (-5625 2700);
DISPLAY INVISIBLE (-5625 2700);
FORCEPROP 1 LAST HDL_TAP TRUE
J 0
(-5300 2525);
DISPLAY 0.872340 (-5300 2525);
DISPLAY INVISIBLE (-5300 2525);
FORCEPROP 1 LAST PATH I53
J 0
(-5627 2650);
DISPLAY 0.872340 (-5627 2650);
PAINT GREEN (-5627 2650);
DISPLAY INVISIBLE (-5627 2650);
FORCEADD TAP..1
(-5625 2600);
FORCEPROP 3 LASTPIN (-5675 2600) SIG_NAME M_G_CPU0_SB_DQ<8>
J 0
(-5665 2610);
DISPLAY 0.659574 (-5665 2610);
PAINT MONO (-5665 2610);
DISPLAY INVISIBLE (-5665 2610);
FORCEPROP 1 LASTPIN (-5675 2600) BN 8
J 0
(-5687 2608);
DISPLAY 0.489362 (-5687 2608);
PAINT GREEN (-5687 2608);
FORCEPROP 2 LAST CDS_LIB mstr_standard
J 0
(-5625 2600);
DISPLAY 0.723404 (-5625 2600);
PAINT MONO (-5625 2600);
DISPLAY INVISIBLE (-5625 2600);
FORCEPROP 1 LAST BODY_TYPE PLUMBING
J 0
(-5625 2650);
DISPLAY 0.872340 (-5625 2650);
PAINT GREEN (-5625 2650);
DISPLAY INVISIBLE (-5625 2650);
FORCEPROP 1 LAST HDL_TAP TRUE
J 0
(-5300 2475);
DISPLAY 0.872340 (-5300 2475);
DISPLAY INVISIBLE (-5300 2475);
FORCEPROP 1 LAST PATH I54
J 0
(-5627 2600);
DISPLAY 0.872340 (-5627 2600);
PAINT GREEN (-5627 2600);
DISPLAY INVISIBLE (-5627 2600);
FORCEADD TAP..1
(-5625 2550);
FORCEPROP 3 LASTPIN (-5675 2550) SIG_NAME M_G_CPU0_SB_DQ<7>
J 0
(-5665 2560);
DISPLAY 0.659574 (-5665 2560);
PAINT MONO (-5665 2560);
DISPLAY INVISIBLE (-5665 2560);
FORCEPROP 1 LASTPIN (-5675 2550) BN 7
J 0
(-5687 2558);
DISPLAY 0.489362 (-5687 2558);
PAINT GREEN (-5687 2558);
FORCEPROP 2 LAST CDS_LIB mstr_standard
J 0
(-5625 2550);
DISPLAY 0.723404 (-5625 2550);
PAINT MONO (-5625 2550);
DISPLAY INVISIBLE (-5625 2550);
FORCEPROP 1 LAST BODY_TYPE PLUMBING
J 0
(-5625 2600);
DISPLAY 0.872340 (-5625 2600);
PAINT GREEN (-5625 2600);
DISPLAY INVISIBLE (-5625 2600);
FORCEPROP 1 LAST HDL_TAP TRUE
J 0
(-5300 2425);
DISPLAY 0.872340 (-5300 2425);
DISPLAY INVISIBLE (-5300 2425);
FORCEPROP 1 LAST PATH I55
J 0
(-5627 2550);
DISPLAY 0.872340 (-5627 2550);
PAINT GREEN (-5627 2550);
DISPLAY INVISIBLE (-5627 2550);
FORCEADD TAP..1
(-5625 2700);
FORCEPROP 3 LASTPIN (-5675 2700) SIG_NAME M_G_CPU0_SB_DQ<10>
J 0
(-5665 2710);
DISPLAY 0.659574 (-5665 2710);
PAINT MONO (-5665 2710);
DISPLAY INVISIBLE (-5665 2710);
FORCEPROP 1 LASTPIN (-5675 2700) BN 10
J 0
(-5687 2708);
DISPLAY 0.489362 (-5687 2708);
PAINT GREEN (-5687 2708);
FORCEPROP 2 LAST CDS_LIB mstr_standard
J 0
(-5625 2700);
DISPLAY 0.723404 (-5625 2700);
PAINT MONO (-5625 2700);
DISPLAY INVISIBLE (-5625 2700);
FORCEPROP 1 LAST BODY_TYPE PLUMBING
J 0
(-5625 2750);
DISPLAY 0.872340 (-5625 2750);
PAINT GREEN (-5625 2750);
DISPLAY INVISIBLE (-5625 2750);
FORCEPROP 1 LAST HDL_TAP TRUE
J 0
(-5300 2575);
DISPLAY 0.872340 (-5300 2575);
DISPLAY INVISIBLE (-5300 2575);
FORCEPROP 1 LAST PATH I56
J 0
(-5627 2700);
DISPLAY 0.872340 (-5627 2700);
PAINT GREEN (-5627 2700);
DISPLAY INVISIBLE (-5627 2700);
FORCEADD TAP..1
(-5625 2750);
FORCEPROP 3 LASTPIN (-5675 2750) SIG_NAME M_G_CPU0_SB_DQ<11>
J 0
(-5665 2760);
DISPLAY 0.659574 (-5665 2760);
PAINT MONO (-5665 2760);
DISPLAY INVISIBLE (-5665 2760);
FORCEPROP 1 LASTPIN (-5675 2750) BN 11
J 0
(-5687 2758);
DISPLAY 0.489362 (-5687 2758);
PAINT GREEN (-5687 2758);
FORCEPROP 2 LAST CDS_LIB mstr_standard
J 0
(-5625 2750);
DISPLAY 0.723404 (-5625 2750);
PAINT MONO (-5625 2750);
DISPLAY INVISIBLE (-5625 2750);
FORCEPROP 1 LAST BODY_TYPE PLUMBING
J 0
(-5625 2800);
DISPLAY 0.872340 (-5625 2800);
PAINT GREEN (-5625 2800);
DISPLAY INVISIBLE (-5625 2800);
FORCEPROP 1 LAST HDL_TAP TRUE
J 0
(-5300 2625);
DISPLAY 0.872340 (-5300 2625);
DISPLAY INVISIBLE (-5300 2625);
FORCEPROP 1 LAST PATH I57
J 0
(-5627 2750);
DISPLAY 0.872340 (-5627 2750);
PAINT GREEN (-5627 2750);
DISPLAY INVISIBLE (-5627 2750);
FORCEADD TAP..1
(-5625 2900);
FORCEPROP 3 LASTPIN (-5675 2900) SIG_NAME M_G_CPU0_SB_DQ<14>
J 0
(-5665 2910);
DISPLAY 0.659574 (-5665 2910);
PAINT MONO (-5665 2910);
DISPLAY INVISIBLE (-5665 2910);
FORCEPROP 1 LASTPIN (-5675 2900) BN 14
J 0
(-5687 2908);
DISPLAY 0.489362 (-5687 2908);
PAINT GREEN (-5687 2908);
FORCEPROP 2 LAST CDS_LIB mstr_standard
J 0
(-5625 2900);
DISPLAY 0.723404 (-5625 2900);
PAINT MONO (-5625 2900);
DISPLAY INVISIBLE (-5625 2900);
FORCEPROP 1 LAST BODY_TYPE PLUMBING
J 0
(-5625 2950);
DISPLAY 0.872340 (-5625 2950);
PAINT GREEN (-5625 2950);
DISPLAY INVISIBLE (-5625 2950);
FORCEPROP 1 LAST HDL_TAP TRUE
J 0
(-5300 2775);
DISPLAY 0.872340 (-5300 2775);
DISPLAY INVISIBLE (-5300 2775);
FORCEPROP 1 LAST PATH I58
J 0
(-5627 2900);
DISPLAY 0.872340 (-5627 2900);
PAINT GREEN (-5627 2900);
DISPLAY INVISIBLE (-5627 2900);
FORCEADD TAP..1
(-5625 2850);
FORCEPROP 3 LASTPIN (-5675 2850) SIG_NAME M_G_CPU0_SB_DQ<13>
J 0
(-5665 2860);
DISPLAY 0.659574 (-5665 2860);
PAINT MONO (-5665 2860);
DISPLAY INVISIBLE (-5665 2860);
FORCEPROP 1 LASTPIN (-5675 2850) BN 13
J 0
(-5687 2858);
DISPLAY 0.489362 (-5687 2858);
PAINT GREEN (-5687 2858);
FORCEPROP 2 LAST CDS_LIB mstr_standard
J 0
(-5625 2850);
DISPLAY 0.723404 (-5625 2850);
PAINT MONO (-5625 2850);
DISPLAY INVISIBLE (-5625 2850);
FORCEPROP 1 LAST BODY_TYPE PLUMBING
J 0
(-5625 2900);
DISPLAY 0.872340 (-5625 2900);
PAINT GREEN (-5625 2900);
DISPLAY INVISIBLE (-5625 2900);
FORCEPROP 1 LAST HDL_TAP TRUE
J 0
(-5300 2725);
DISPLAY 0.872340 (-5300 2725);
DISPLAY INVISIBLE (-5300 2725);
FORCEPROP 1 LAST PATH I59
J 0
(-5627 2850);
DISPLAY 0.872340 (-5627 2850);
PAINT GREEN (-5627 2850);
DISPLAY INVISIBLE (-5627 2850);
FORCEADD OFFPAGE..1
(-7925 2900);
FORCEPROP 2 LAST $XR0 91 
J 0
(-8176 2900);
DISPLAY 0.638298 (-8176 2900);
PAINT MONO (-8176 2900);
FORCEPROP 2 LAST PATH I6
J 0
(-8175 2950);
DISPLAY 1.021277 (-8175 2950);
DISPLAY INVISIBLE (-8175 2950);
FORCEPROP 1 LAST COMMENT_BODY TRUE
J 0
(-7800 2800);
DISPLAY 0.872340 (-7800 2800);
PAINT GREEN (-7800 2800);
DISPLAY INVISIBLE (-7800 2800);
FORCEPROP 1 LAST OFFPAGE TRUE
J 0
(-7600 2775);
DISPLAY 0.872340 (-7600 2775);
PAINT GREEN (-7600 2775);
DISPLAY INVISIBLE (-7600 2775);
FORCEPROP 2 LAST CDS_LIB mstr_standard
J 0
(-7925 2900);
DISPLAY 0.808511 (-7925 2900);
DISPLAY INVISIBLE (-7925 2900);
FORCEADD TAP..1
(-5625 2800);
FORCEPROP 3 LASTPIN (-5675 2800) SIG_NAME M_G_CPU0_SB_DQ<12>
J 0
(-5665 2810);
DISPLAY 0.659574 (-5665 2810);
PAINT MONO (-5665 2810);
DISPLAY INVISIBLE (-5665 2810);
FORCEPROP 1 LASTPIN (-5675 2800) BN 12
J 0
(-5687 2808);
DISPLAY 0.489362 (-5687 2808);
PAINT GREEN (-5687 2808);
FORCEPROP 2 LAST CDS_LIB mstr_standard
J 0
(-5625 2800);
DISPLAY 0.723404 (-5625 2800);
PAINT MONO (-5625 2800);
DISPLAY INVISIBLE (-5625 2800);
FORCEPROP 1 LAST BODY_TYPE PLUMBING
J 0
(-5625 2850);
DISPLAY 0.872340 (-5625 2850);
PAINT GREEN (-5625 2850);
DISPLAY INVISIBLE (-5625 2850);
FORCEPROP 1 LAST HDL_TAP TRUE
J 0
(-5300 2675);
DISPLAY 0.872340 (-5300 2675);
DISPLAY INVISIBLE (-5300 2675);
FORCEPROP 1 LAST PATH I60
J 0
(-5627 2800);
DISPLAY 0.872340 (-5627 2800);
PAINT GREEN (-5627 2800);
DISPLAY INVISIBLE (-5627 2800);
FORCEADD TAP..1
(-5625 3000);
FORCEPROP 3 LASTPIN (-5675 3000) SIG_NAME M_G_CPU0_SB_DQ<16>
J 0
(-5665 3010);
DISPLAY 0.659574 (-5665 3010);
PAINT MONO (-5665 3010);
DISPLAY INVISIBLE (-5665 3010);
FORCEPROP 1 LASTPIN (-5675 3000) BN 16
J 0
(-5687 3008);
DISPLAY 0.489362 (-5687 3008);
PAINT GREEN (-5687 3008);
FORCEPROP 2 LAST CDS_LIB mstr_standard
J 0
(-5625 3000);
DISPLAY 0.723404 (-5625 3000);
PAINT MONO (-5625 3000);
DISPLAY INVISIBLE (-5625 3000);
FORCEPROP 1 LAST BODY_TYPE PLUMBING
J 0
(-5625 3050);
DISPLAY 0.872340 (-5625 3050);
PAINT GREEN (-5625 3050);
DISPLAY INVISIBLE (-5625 3050);
FORCEPROP 1 LAST HDL_TAP TRUE
J 0
(-5300 2875);
DISPLAY 0.872340 (-5300 2875);
DISPLAY INVISIBLE (-5300 2875);
FORCEPROP 1 LAST PATH I61
J 0
(-5627 3000);
DISPLAY 0.872340 (-5627 3000);
PAINT GREEN (-5627 3000);
DISPLAY INVISIBLE (-5627 3000);
FORCEADD TAP..1
(-5625 2950);
FORCEPROP 3 LASTPIN (-5675 2950) SIG_NAME M_G_CPU0_SB_DQ<15>
J 0
(-5665 2960);
DISPLAY 0.659574 (-5665 2960);
PAINT MONO (-5665 2960);
DISPLAY INVISIBLE (-5665 2960);
FORCEPROP 1 LASTPIN (-5675 2950) BN 15
J 0
(-5687 2958);
DISPLAY 0.489362 (-5687 2958);
PAINT GREEN (-5687 2958);
FORCEPROP 2 LAST CDS_LIB mstr_standard
J 0
(-5625 2950);
DISPLAY 0.723404 (-5625 2950);
PAINT MONO (-5625 2950);
DISPLAY INVISIBLE (-5625 2950);
FORCEPROP 1 LAST BODY_TYPE PLUMBING
J 0
(-5625 3000);
DISPLAY 0.872340 (-5625 3000);
PAINT GREEN (-5625 3000);
DISPLAY INVISIBLE (-5625 3000);
FORCEPROP 1 LAST HDL_TAP TRUE
J 0
(-5300 2825);
DISPLAY 0.872340 (-5300 2825);
DISPLAY INVISIBLE (-5300 2825);
FORCEPROP 1 LAST PATH I62
J 0
(-5627 2950);
DISPLAY 0.872340 (-5627 2950);
PAINT GREEN (-5627 2950);
DISPLAY INVISIBLE (-5627 2950);
FORCEADD TAP..1
(-5625 3050);
FORCEPROP 3 LASTPIN (-5675 3050) SIG_NAME M_G_CPU0_SB_DQ<17>
J 0
(-5665 3060);
DISPLAY 0.659574 (-5665 3060);
PAINT MONO (-5665 3060);
DISPLAY INVISIBLE (-5665 3060);
FORCEPROP 1 LASTPIN (-5675 3050) BN 17
J 0
(-5687 3058);
DISPLAY 0.489362 (-5687 3058);
PAINT GREEN (-5687 3058);
FORCEPROP 2 LAST CDS_LIB mstr_standard
J 0
(-5625 3050);
DISPLAY 0.723404 (-5625 3050);
PAINT MONO (-5625 3050);
DISPLAY INVISIBLE (-5625 3050);
FORCEPROP 1 LAST BODY_TYPE PLUMBING
J 0
(-5625 3100);
DISPLAY 0.872340 (-5625 3100);
PAINT GREEN (-5625 3100);
DISPLAY INVISIBLE (-5625 3100);
FORCEPROP 1 LAST HDL_TAP TRUE
J 0
(-5300 2925);
DISPLAY 0.872340 (-5300 2925);
DISPLAY INVISIBLE (-5300 2925);
FORCEPROP 1 LAST PATH I63
J 0
(-5627 3050);
DISPLAY 0.872340 (-5627 3050);
PAINT GREEN (-5627 3050);
DISPLAY INVISIBLE (-5627 3050);
FORCEADD TAP..1
(-5625 3150);
FORCEPROP 3 LASTPIN (-5675 3150) SIG_NAME M_G_CPU0_SB_DQ<19>
J 0
(-5665 3160);
DISPLAY 0.659574 (-5665 3160);
PAINT MONO (-5665 3160);
DISPLAY INVISIBLE (-5665 3160);
FORCEPROP 1 LASTPIN (-5675 3150) BN 19
J 0
(-5687 3158);
DISPLAY 0.489362 (-5687 3158);
PAINT GREEN (-5687 3158);
FORCEPROP 2 LAST CDS_LIB mstr_standard
J 0
(-5625 3150);
DISPLAY 0.723404 (-5625 3150);
PAINT MONO (-5625 3150);
DISPLAY INVISIBLE (-5625 3150);
FORCEPROP 1 LAST BODY_TYPE PLUMBING
J 0
(-5625 3200);
DISPLAY 0.872340 (-5625 3200);
PAINT GREEN (-5625 3200);
DISPLAY INVISIBLE (-5625 3200);
FORCEPROP 1 LAST HDL_TAP TRUE
J 0
(-5300 3025);
DISPLAY 0.872340 (-5300 3025);
DISPLAY INVISIBLE (-5300 3025);
FORCEPROP 1 LAST PATH I64
J 0
(-5627 3150);
DISPLAY 0.872340 (-5627 3150);
PAINT GREEN (-5627 3150);
DISPLAY INVISIBLE (-5627 3150);
FORCEADD TAP..1
(-5625 3100);
FORCEPROP 3 LASTPIN (-5675 3100) SIG_NAME M_G_CPU0_SB_DQ<18>
J 0
(-5665 3110);
DISPLAY 0.659574 (-5665 3110);
PAINT MONO (-5665 3110);
DISPLAY INVISIBLE (-5665 3110);
FORCEPROP 1 LASTPIN (-5675 3100) BN 18
J 0
(-5687 3108);
DISPLAY 0.489362 (-5687 3108);
PAINT GREEN (-5687 3108);
FORCEPROP 2 LAST CDS_LIB mstr_standard
J 0
(-5625 3100);
DISPLAY 0.723404 (-5625 3100);
PAINT MONO (-5625 3100);
DISPLAY INVISIBLE (-5625 3100);
FORCEPROP 1 LAST BODY_TYPE PLUMBING
J 0
(-5625 3150);
DISPLAY 0.872340 (-5625 3150);
PAINT GREEN (-5625 3150);
DISPLAY INVISIBLE (-5625 3150);
FORCEPROP 1 LAST HDL_TAP TRUE
J 0
(-5300 2975);
DISPLAY 0.872340 (-5300 2975);
DISPLAY INVISIBLE (-5300 2975);
FORCEPROP 1 LAST PATH I65
J 0
(-5627 3100);
DISPLAY 0.872340 (-5627 3100);
PAINT GREEN (-5627 3100);
DISPLAY INVISIBLE (-5627 3100);
FORCEADD TAP..1
(-5625 3200);
FORCEPROP 3 LASTPIN (-5675 3200) SIG_NAME M_G_CPU0_SB_DQ<20>
J 0
(-5665 3210);
DISPLAY 0.659574 (-5665 3210);
PAINT MONO (-5665 3210);
DISPLAY INVISIBLE (-5665 3210);
FORCEPROP 1 LASTPIN (-5675 3200) BN 20
J 0
(-5687 3208);
DISPLAY 0.489362 (-5687 3208);
PAINT GREEN (-5687 3208);
FORCEPROP 2 LAST CDS_LIB mstr_standard
J 0
(-5625 3200);
DISPLAY 0.723404 (-5625 3200);
PAINT MONO (-5625 3200);
DISPLAY INVISIBLE (-5625 3200);
FORCEPROP 1 LAST BODY_TYPE PLUMBING
J 0
(-5625 3250);
DISPLAY 0.872340 (-5625 3250);
PAINT GREEN (-5625 3250);
DISPLAY INVISIBLE (-5625 3250);
FORCEPROP 1 LAST HDL_TAP TRUE
J 0
(-5300 3075);
DISPLAY 0.872340 (-5300 3075);
DISPLAY INVISIBLE (-5300 3075);
FORCEPROP 1 LAST PATH I66
J 0
(-5627 3200);
DISPLAY 0.872340 (-5627 3200);
PAINT GREEN (-5627 3200);
DISPLAY INVISIBLE (-5627 3200);
FORCEADD TAP..1
(-5625 3250);
FORCEPROP 3 LASTPIN (-5675 3250) SIG_NAME M_G_CPU0_SB_DQ<21>
J 0
(-5665 3260);
DISPLAY 0.659574 (-5665 3260);
PAINT MONO (-5665 3260);
DISPLAY INVISIBLE (-5665 3260);
FORCEPROP 1 LASTPIN (-5675 3250) BN 21
J 0
(-5687 3258);
DISPLAY 0.489362 (-5687 3258);
PAINT GREEN (-5687 3258);
FORCEPROP 2 LAST CDS_LIB mstr_standard
J 0
(-5625 3250);
DISPLAY 0.723404 (-5625 3250);
PAINT MONO (-5625 3250);
DISPLAY INVISIBLE (-5625 3250);
FORCEPROP 1 LAST BODY_TYPE PLUMBING
J 0
(-5625 3300);
DISPLAY 0.872340 (-5625 3300);
PAINT GREEN (-5625 3300);
DISPLAY INVISIBLE (-5625 3300);
FORCEPROP 1 LAST HDL_TAP TRUE
J 0
(-5300 3125);
DISPLAY 0.872340 (-5300 3125);
DISPLAY INVISIBLE (-5300 3125);
FORCEPROP 1 LAST PATH I67
J 0
(-5627 3250);
DISPLAY 0.872340 (-5627 3250);
PAINT GREEN (-5627 3250);
DISPLAY INVISIBLE (-5627 3250);
FORCEADD TAP..1
(-5625 3300);
FORCEPROP 3 LASTPIN (-5675 3300) SIG_NAME M_G_CPU0_SB_DQ<22>
J 0
(-5665 3310);
DISPLAY 0.659574 (-5665 3310);
PAINT MONO (-5665 3310);
DISPLAY INVISIBLE (-5665 3310);
FORCEPROP 1 LASTPIN (-5675 3300) BN 22
J 0
(-5687 3308);
DISPLAY 0.489362 (-5687 3308);
PAINT GREEN (-5687 3308);
FORCEPROP 2 LAST CDS_LIB mstr_standard
J 0
(-5625 3300);
DISPLAY 0.723404 (-5625 3300);
PAINT MONO (-5625 3300);
DISPLAY INVISIBLE (-5625 3300);
FORCEPROP 1 LAST BODY_TYPE PLUMBING
J 0
(-5625 3350);
DISPLAY 0.872340 (-5625 3350);
PAINT GREEN (-5625 3350);
DISPLAY INVISIBLE (-5625 3350);
FORCEPROP 1 LAST HDL_TAP TRUE
J 0
(-5300 3175);
DISPLAY 0.872340 (-5300 3175);
DISPLAY INVISIBLE (-5300 3175);
FORCEPROP 1 LAST PATH I68
J 0
(-5627 3300);
DISPLAY 0.872340 (-5627 3300);
PAINT GREEN (-5627 3300);
DISPLAY INVISIBLE (-5627 3300);
FORCEADD TAP..1
(-5625 3400);
FORCEPROP 3 LASTPIN (-5675 3400) SIG_NAME M_G_CPU0_SB_DQ<24>
J 0
(-5665 3410);
DISPLAY 0.659574 (-5665 3410);
PAINT MONO (-5665 3410);
DISPLAY INVISIBLE (-5665 3410);
FORCEPROP 1 LASTPIN (-5675 3400) BN 24
J 0
(-5687 3408);
DISPLAY 0.489362 (-5687 3408);
PAINT GREEN (-5687 3408);
FORCEPROP 2 LAST CDS_LIB mstr_standard
J 0
(-5625 3400);
DISPLAY 0.723404 (-5625 3400);
PAINT MONO (-5625 3400);
DISPLAY INVISIBLE (-5625 3400);
FORCEPROP 1 LAST BODY_TYPE PLUMBING
J 0
(-5625 3450);
DISPLAY 0.872340 (-5625 3450);
PAINT GREEN (-5625 3450);
DISPLAY INVISIBLE (-5625 3450);
FORCEPROP 1 LAST HDL_TAP TRUE
J 0
(-5300 3275);
DISPLAY 0.872340 (-5300 3275);
DISPLAY INVISIBLE (-5300 3275);
FORCEPROP 1 LAST PATH I69
J 0
(-5627 3400);
DISPLAY 0.872340 (-5627 3400);
PAINT GREEN (-5627 3400);
DISPLAY INVISIBLE (-5627 3400);
FORCEADD OFFPAGE..5
(-7925 3050);
FORCEPROP 2 LAST $XR0 16 
J 0
(-8149 3050);
DISPLAY 0.638298 (-8149 3050);
PAINT MONO (-8149 3050);
FORCEPROP 2 LAST PATH I7
J 0
(-8175 3100);
DISPLAY 1.021277 (-8175 3100);
DISPLAY INVISIBLE (-8175 3100);
FORCEPROP 1 LAST COMMENT_BODY TRUE
J 0
(-7825 2975);
DISPLAY 0.872340 (-7825 2975);
PAINT GREEN (-7825 2975);
DISPLAY INVISIBLE (-7825 2975);
FORCEPROP 1 LAST OFFPAGE TRUE
J 0
(-7600 2925);
DISPLAY 0.872340 (-7600 2925);
PAINT GREEN (-7600 2925);
DISPLAY INVISIBLE (-7600 2925);
FORCEPROP 2 LAST CDS_LIB mstr_standard
J 0
(-7925 3050);
DISPLAY INVISIBLE (-7925 3050);
FORCEADD TAP..1
(-5625 3350);
FORCEPROP 3 LASTPIN (-5675 3350) SIG_NAME M_G_CPU0_SB_DQ<23>
J 0
(-5665 3360);
DISPLAY 0.659574 (-5665 3360);
PAINT MONO (-5665 3360);
DISPLAY INVISIBLE (-5665 3360);
FORCEPROP 1 LASTPIN (-5675 3350) BN 23
J 0
(-5687 3358);
DISPLAY 0.489362 (-5687 3358);
PAINT GREEN (-5687 3358);
FORCEPROP 2 LAST CDS_LIB mstr_standard
J 0
(-5625 3350);
DISPLAY 0.723404 (-5625 3350);
PAINT MONO (-5625 3350);
DISPLAY INVISIBLE (-5625 3350);
FORCEPROP 1 LAST BODY_TYPE PLUMBING
J 0
(-5625 3400);
DISPLAY 0.872340 (-5625 3400);
PAINT GREEN (-5625 3400);
DISPLAY INVISIBLE (-5625 3400);
FORCEPROP 1 LAST HDL_TAP TRUE
J 0
(-5300 3225);
DISPLAY 0.872340 (-5300 3225);
DISPLAY INVISIBLE (-5300 3225);
FORCEPROP 1 LAST PATH I70
J 0
(-5627 3350);
DISPLAY 0.872340 (-5627 3350);
PAINT GREEN (-5627 3350);
DISPLAY INVISIBLE (-5627 3350);
FORCEADD TAP..1
(-5625 3450);
FORCEPROP 3 LASTPIN (-5675 3450) SIG_NAME M_G_CPU0_SB_DQ<25>
J 0
(-5665 3460);
DISPLAY 0.659574 (-5665 3460);
PAINT MONO (-5665 3460);
DISPLAY INVISIBLE (-5665 3460);
FORCEPROP 1 LASTPIN (-5675 3450) BN 25
J 0
(-5687 3458);
DISPLAY 0.489362 (-5687 3458);
PAINT GREEN (-5687 3458);
FORCEPROP 2 LAST CDS_LIB mstr_standard
J 0
(-5625 3450);
DISPLAY 0.723404 (-5625 3450);
PAINT MONO (-5625 3450);
DISPLAY INVISIBLE (-5625 3450);
FORCEPROP 1 LAST BODY_TYPE PLUMBING
J 0
(-5625 3500);
DISPLAY 0.872340 (-5625 3500);
PAINT GREEN (-5625 3500);
DISPLAY INVISIBLE (-5625 3500);
FORCEPROP 1 LAST HDL_TAP TRUE
J 0
(-5300 3325);
DISPLAY 0.872340 (-5300 3325);
DISPLAY INVISIBLE (-5300 3325);
FORCEPROP 1 LAST PATH I71
J 0
(-5627 3450);
DISPLAY 0.872340 (-5627 3450);
PAINT GREEN (-5627 3450);
DISPLAY INVISIBLE (-5627 3450);
FORCEADD TAP..1
(-5625 3500);
FORCEPROP 3 LASTPIN (-5675 3500) SIG_NAME M_G_CPU0_SB_DQ<26>
J 0
(-5665 3510);
DISPLAY 0.659574 (-5665 3510);
PAINT MONO (-5665 3510);
DISPLAY INVISIBLE (-5665 3510);
FORCEPROP 1 LASTPIN (-5675 3500) BN 26
J 0
(-5687 3508);
DISPLAY 0.489362 (-5687 3508);
PAINT GREEN (-5687 3508);
FORCEPROP 2 LAST CDS_LIB mstr_standard
J 0
(-5625 3500);
DISPLAY 0.723404 (-5625 3500);
PAINT MONO (-5625 3500);
DISPLAY INVISIBLE (-5625 3500);
FORCEPROP 1 LAST BODY_TYPE PLUMBING
J 0
(-5625 3550);
DISPLAY 0.872340 (-5625 3550);
PAINT GREEN (-5625 3550);
DISPLAY INVISIBLE (-5625 3550);
FORCEPROP 1 LAST HDL_TAP TRUE
J 0
(-5300 3375);
DISPLAY 0.872340 (-5300 3375);
DISPLAY INVISIBLE (-5300 3375);
FORCEPROP 1 LAST PATH I72
J 0
(-5627 3500);
DISPLAY 0.872340 (-5627 3500);
PAINT GREEN (-5627 3500);
DISPLAY INVISIBLE (-5627 3500);
FORCEADD TAP..1
(-5625 3550);
FORCEPROP 3 LASTPIN (-5675 3550) SIG_NAME M_G_CPU0_SB_DQ<27>
J 0
(-5665 3560);
DISPLAY 0.659574 (-5665 3560);
PAINT MONO (-5665 3560);
DISPLAY INVISIBLE (-5665 3560);
FORCEPROP 1 LASTPIN (-5675 3550) BN 27
J 0
(-5687 3558);
DISPLAY 0.489362 (-5687 3558);
PAINT GREEN (-5687 3558);
FORCEPROP 2 LAST CDS_LIB mstr_standard
J 0
(-5625 3550);
DISPLAY 0.723404 (-5625 3550);
PAINT MONO (-5625 3550);
DISPLAY INVISIBLE (-5625 3550);
FORCEPROP 1 LAST BODY_TYPE PLUMBING
J 0
(-5625 3600);
DISPLAY 0.872340 (-5625 3600);
PAINT GREEN (-5625 3600);
DISPLAY INVISIBLE (-5625 3600);
FORCEPROP 1 LAST HDL_TAP TRUE
J 0
(-5300 3425);
DISPLAY 0.872340 (-5300 3425);
DISPLAY INVISIBLE (-5300 3425);
FORCEPROP 1 LAST PATH I73
J 0
(-5627 3550);
DISPLAY 0.872340 (-5627 3550);
PAINT GREEN (-5627 3550);
DISPLAY INVISIBLE (-5627 3550);
FORCEADD TAP..1
(-5625 3650);
FORCEPROP 3 LASTPIN (-5675 3650) SIG_NAME M_G_CPU0_SB_DQ<29>
J 0
(-5665 3660);
DISPLAY 0.659574 (-5665 3660);
PAINT MONO (-5665 3660);
DISPLAY INVISIBLE (-5665 3660);
FORCEPROP 1 LASTPIN (-5675 3650) BN 29
J 0
(-5687 3658);
DISPLAY 0.489362 (-5687 3658);
PAINT GREEN (-5687 3658);
FORCEPROP 2 LAST CDS_LIB mstr_standard
J 0
(-5625 3650);
DISPLAY 0.723404 (-5625 3650);
PAINT MONO (-5625 3650);
DISPLAY INVISIBLE (-5625 3650);
FORCEPROP 1 LAST BODY_TYPE PLUMBING
J 0
(-5625 3700);
DISPLAY 0.872340 (-5625 3700);
PAINT GREEN (-5625 3700);
DISPLAY INVISIBLE (-5625 3700);
FORCEPROP 1 LAST HDL_TAP TRUE
J 0
(-5300 3525);
DISPLAY 0.872340 (-5300 3525);
DISPLAY INVISIBLE (-5300 3525);
FORCEPROP 1 LAST PATH I74
J 0
(-5627 3650);
DISPLAY 0.872340 (-5627 3650);
PAINT GREEN (-5627 3650);
DISPLAY INVISIBLE (-5627 3650);
FORCEADD TAP..1
(-5625 3600);
FORCEPROP 3 LASTPIN (-5675 3600) SIG_NAME M_G_CPU0_SB_DQ<28>
J 0
(-5665 3610);
DISPLAY 0.659574 (-5665 3610);
PAINT MONO (-5665 3610);
DISPLAY INVISIBLE (-5665 3610);
FORCEPROP 1 LASTPIN (-5675 3600) BN 28
J 0
(-5687 3608);
DISPLAY 0.489362 (-5687 3608);
PAINT GREEN (-5687 3608);
FORCEPROP 2 LAST CDS_LIB mstr_standard
J 0
(-5625 3600);
DISPLAY 0.723404 (-5625 3600);
PAINT MONO (-5625 3600);
DISPLAY INVISIBLE (-5625 3600);
FORCEPROP 1 LAST BODY_TYPE PLUMBING
J 0
(-5625 3650);
DISPLAY 0.872340 (-5625 3650);
PAINT GREEN (-5625 3650);
DISPLAY INVISIBLE (-5625 3650);
FORCEPROP 1 LAST HDL_TAP TRUE
J 0
(-5300 3475);
DISPLAY 0.872340 (-5300 3475);
DISPLAY INVISIBLE (-5300 3475);
FORCEPROP 1 LAST PATH I75
J 0
(-5627 3600);
DISPLAY 0.872340 (-5627 3600);
PAINT GREEN (-5627 3600);
DISPLAY INVISIBLE (-5627 3600);
FORCEADD TAP..1
(-5625 3700);
FORCEPROP 3 LASTPIN (-5675 3700) SIG_NAME M_G_CPU0_SB_DQ<30>
J 0
(-5665 3710);
DISPLAY 0.659574 (-5665 3710);
PAINT MONO (-5665 3710);
DISPLAY INVISIBLE (-5665 3710);
FORCEPROP 1 LASTPIN (-5675 3700) BN 30
J 0
(-5687 3708);
DISPLAY 0.489362 (-5687 3708);
PAINT GREEN (-5687 3708);
FORCEPROP 2 LAST CDS_LIB mstr_standard
J 0
(-5625 3700);
DISPLAY 0.723404 (-5625 3700);
PAINT MONO (-5625 3700);
DISPLAY INVISIBLE (-5625 3700);
FORCEPROP 1 LAST BODY_TYPE PLUMBING
J 0
(-5625 3750);
DISPLAY 0.872340 (-5625 3750);
PAINT GREEN (-5625 3750);
DISPLAY INVISIBLE (-5625 3750);
FORCEPROP 1 LAST HDL_TAP TRUE
J 0
(-5300 3575);
DISPLAY 0.872340 (-5300 3575);
DISPLAY INVISIBLE (-5300 3575);
FORCEPROP 1 LAST PATH I76
J 0
(-5627 3700);
DISPLAY 0.872340 (-5627 3700);
PAINT GREEN (-5627 3700);
DISPLAY INVISIBLE (-5627 3700);
FORCEADD TAP..1
(-5625 3750);
FORCEPROP 3 LASTPIN (-5675 3750) SIG_NAME M_G_CPU0_SB_DQ<31>
J 0
(-5665 3760);
DISPLAY 0.659574 (-5665 3760);
PAINT MONO (-5665 3760);
DISPLAY INVISIBLE (-5665 3760);
FORCEPROP 1 LASTPIN (-5675 3750) BN 31
J 0
(-5687 3758);
DISPLAY 0.489362 (-5687 3758);
PAINT GREEN (-5687 3758);
FORCEPROP 2 LAST CDS_LIB mstr_standard
J 0
(-5625 3750);
DISPLAY 0.723404 (-5625 3750);
PAINT MONO (-5625 3750);
DISPLAY INVISIBLE (-5625 3750);
FORCEPROP 1 LAST BODY_TYPE PLUMBING
J 0
(-5625 3800);
DISPLAY 0.872340 (-5625 3800);
PAINT GREEN (-5625 3800);
DISPLAY INVISIBLE (-5625 3800);
FORCEPROP 1 LAST HDL_TAP TRUE
J 0
(-5300 3625);
DISPLAY 0.872340 (-5300 3625);
DISPLAY INVISIBLE (-5300 3625);
FORCEPROP 1 LAST PATH I77
J 0
(-5627 3750);
DISPLAY 0.872340 (-5627 3750);
PAINT GREEN (-5627 3750);
DISPLAY INVISIBLE (-5627 3750);
FORCEADD TAP..1
(-5625 3900);
FORCEPROP 3 LASTPIN (-5675 3900) SIG_NAME M_G_CPU0_SA_DQ<1>
J 0
(-5665 3910);
DISPLAY 0.659574 (-5665 3910);
PAINT MONO (-5665 3910);
DISPLAY INVISIBLE (-5665 3910);
FORCEPROP 1 LASTPIN (-5675 3900) BN 1
J 0
(-5687 3908);
DISPLAY 0.489362 (-5687 3908);
PAINT GREEN (-5687 3908);
FORCEPROP 2 LAST CDS_LIB mstr_standard
J 0
(-5625 3900);
DISPLAY 0.723404 (-5625 3900);
PAINT MONO (-5625 3900);
DISPLAY INVISIBLE (-5625 3900);
FORCEPROP 1 LAST BODY_TYPE PLUMBING
J 0
(-5625 3950);
DISPLAY 0.872340 (-5625 3950);
PAINT GREEN (-5625 3950);
DISPLAY INVISIBLE (-5625 3950);
FORCEPROP 1 LAST HDL_TAP TRUE
J 0
(-5300 3775);
DISPLAY 0.872340 (-5300 3775);
DISPLAY INVISIBLE (-5300 3775);
FORCEPROP 1 LAST PATH I78
J 0
(-5627 3900);
DISPLAY 0.872340 (-5627 3900);
PAINT GREEN (-5627 3900);
DISPLAY INVISIBLE (-5627 3900);
FORCEADD TAP..1
(-5625 3850);
FORCEPROP 3 LASTPIN (-5675 3850) SIG_NAME M_G_CPU0_SA_DQ<0>
J 0
(-5665 3860);
DISPLAY 0.659574 (-5665 3860);
PAINT MONO (-5665 3860);
DISPLAY INVISIBLE (-5665 3860);
FORCEPROP 1 LASTPIN (-5675 3850) BN 0
J 0
(-5687 3858);
DISPLAY 0.489362 (-5687 3858);
PAINT GREEN (-5687 3858);
FORCEPROP 2 LAST CDS_LIB mstr_standard
J 0
(-5625 3850);
DISPLAY 0.723404 (-5625 3850);
PAINT MONO (-5625 3850);
DISPLAY INVISIBLE (-5625 3850);
FORCEPROP 1 LAST BODY_TYPE PLUMBING
J 0
(-5625 3900);
DISPLAY 0.872340 (-5625 3900);
PAINT GREEN (-5625 3900);
DISPLAY INVISIBLE (-5625 3900);
FORCEPROP 1 LAST HDL_TAP TRUE
J 0
(-5300 3725);
DISPLAY 0.872340 (-5300 3725);
DISPLAY INVISIBLE (-5300 3725);
FORCEPROP 1 LAST PATH I79
J 0
(-5627 3850);
DISPLAY 0.872340 (-5627 3850);
PAINT GREEN (-5627 3850);
DISPLAY INVISIBLE (-5627 3850);
FORCEADD VCC_CORE..1
(-8400 3450);
FORCEPROP 3 LASTPIN (-8400 3400) SIG_NAME P3V3_STBY\g
J 0
(-8390 3410);
DISPLAY 0.659574 (-8390 3410);
PAINT MONO (-8390 3410);
DISPLAY INVISIBLE (-8390 3410);
FORCEPROP 1 LAST HDL_POWER P3V3_STBY
J 1
(-8400 3500);
DISPLAY 0.489362 (-8400 3500);
PAINT GREEN (-8400 3500);
FORCEPROP 2 LAST CDS_LIB mstr_symbols
J 0
(-8400 3450);
PAINT MONO (-8400 3450);
DISPLAY INVISIBLE (-8400 3450);
FORCEPROP 1 LAST PATH I8
J 0
(-8350 3475);
DISPLAY 0.872340 (-8350 3475);
PAINT AQUA (-8350 3475);
DISPLAY INVISIBLE (-8350 3475);
FORCEPROP 0 LAST VOLTAGE 3.3
J 0
(-8675 3600);
DISPLAY 1.021277 (-8675 3600);
PAINT SKYBLUE (-8675 3600);
DISPLAY INVISIBLE (-8675 3600);
FORCEPROP 2 LAST ROOM PVCCINFAON_CPU0_CTRL
J 0
(-8400 3550);
DISPLAY 0.808511 (-8400 3550);
PAINT RED (-8400 3550);
DISPLAY INVISIBLE (-8400 3550);
FORCEADD TAP..1
(-5625 4000);
FORCEPROP 3 LASTPIN (-5675 4000) SIG_NAME M_G_CPU0_SA_DQ<3>
J 0
(-5665 4010);
DISPLAY 0.659574 (-5665 4010);
PAINT MONO (-5665 4010);
DISPLAY INVISIBLE (-5665 4010);
FORCEPROP 1 LASTPIN (-5675 4000) BN 3
J 0
(-5687 4008);
DISPLAY 0.489362 (-5687 4008);
PAINT GREEN (-5687 4008);
FORCEPROP 2 LAST CDS_LIB mstr_standard
J 0
(-5625 4000);
DISPLAY 0.723404 (-5625 4000);
PAINT MONO (-5625 4000);
DISPLAY INVISIBLE (-5625 4000);
FORCEPROP 1 LAST BODY_TYPE PLUMBING
J 0
(-5625 4050);
DISPLAY 0.872340 (-5625 4050);
PAINT GREEN (-5625 4050);
DISPLAY INVISIBLE (-5625 4050);
FORCEPROP 1 LAST HDL_TAP TRUE
J 0
(-5300 3875);
DISPLAY 0.872340 (-5300 3875);
DISPLAY INVISIBLE (-5300 3875);
FORCEPROP 1 LAST PATH I80
J 0
(-5627 4000);
DISPLAY 0.872340 (-5627 4000);
PAINT GREEN (-5627 4000);
DISPLAY INVISIBLE (-5627 4000);
FORCEADD TAP..1
(-5625 4050);
FORCEPROP 3 LASTPIN (-5675 4050) SIG_NAME M_G_CPU0_SA_DQ<4>
J 0
(-5665 4060);
DISPLAY 0.659574 (-5665 4060);
PAINT MONO (-5665 4060);
DISPLAY INVISIBLE (-5665 4060);
FORCEPROP 1 LASTPIN (-5675 4050) BN 4
J 0
(-5687 4058);
DISPLAY 0.489362 (-5687 4058);
PAINT GREEN (-5687 4058);
FORCEPROP 2 LAST CDS_LIB mstr_standard
J 0
(-5625 4050);
DISPLAY 0.723404 (-5625 4050);
PAINT MONO (-5625 4050);
DISPLAY INVISIBLE (-5625 4050);
FORCEPROP 1 LAST BODY_TYPE PLUMBING
J 0
(-5625 4100);
DISPLAY 0.872340 (-5625 4100);
PAINT GREEN (-5625 4100);
DISPLAY INVISIBLE (-5625 4100);
FORCEPROP 1 LAST HDL_TAP TRUE
J 0
(-5300 3925);
DISPLAY 0.872340 (-5300 3925);
DISPLAY INVISIBLE (-5300 3925);
FORCEPROP 1 LAST PATH I81
J 0
(-5627 4050);
DISPLAY 0.872340 (-5627 4050);
PAINT GREEN (-5627 4050);
DISPLAY INVISIBLE (-5627 4050);
FORCEADD TAP..1
(-5625 3950);
FORCEPROP 3 LASTPIN (-5675 3950) SIG_NAME M_G_CPU0_SA_DQ<2>
J 0
(-5665 3960);
DISPLAY 0.659574 (-5665 3960);
PAINT MONO (-5665 3960);
DISPLAY INVISIBLE (-5665 3960);
FORCEPROP 1 LASTPIN (-5675 3950) BN 2
J 0
(-5687 3958);
DISPLAY 0.489362 (-5687 3958);
PAINT GREEN (-5687 3958);
FORCEPROP 2 LAST CDS_LIB mstr_standard
J 0
(-5625 3950);
DISPLAY 0.723404 (-5625 3950);
PAINT MONO (-5625 3950);
DISPLAY INVISIBLE (-5625 3950);
FORCEPROP 1 LAST BODY_TYPE PLUMBING
J 0
(-5625 4000);
DISPLAY 0.872340 (-5625 4000);
PAINT GREEN (-5625 4000);
DISPLAY INVISIBLE (-5625 4000);
FORCEPROP 1 LAST HDL_TAP TRUE
J 0
(-5300 3825);
DISPLAY 0.872340 (-5300 3825);
DISPLAY INVISIBLE (-5300 3825);
FORCEPROP 1 LAST PATH I82
J 0
(-5627 3950);
DISPLAY 0.872340 (-5627 3950);
PAINT GREEN (-5627 3950);
DISPLAY INVISIBLE (-5627 3950);
FORCEADD OFFPAGE..3
(-5025 3800);
FORCEPROP 2 LAST $XR0 16 
J 0
(-4811 3800);
DISPLAY 0.638298 (-4811 3800);
PAINT MONO (-4811 3800);
FORCEPROP 2 LAST PATH I83
J 0
(-4700 3850);
DISPLAY 1.021277 (-4700 3850);
DISPLAY INVISIBLE (-4700 3850);
FORCEPROP 1 LAST COMMENT_BODY TRUE
J 0
(-5075 3700);
DISPLAY 0.872340 (-5075 3700);
PAINT GREEN (-5075 3700);
DISPLAY INVISIBLE (-5075 3700);
FORCEPROP 1 LAST OFFPAGE TRUE
J 0
(-4700 3675);
DISPLAY 0.872340 (-4700 3675);
PAINT GREEN (-4700 3675);
DISPLAY INVISIBLE (-4700 3675);
FORCEPROP 2 LAST CDS_LIB mstr_standard
J 0
(-5025 3800);
DISPLAY 0.723404 (-5025 3800);
PAINT MONO (-5025 3800);
DISPLAY INVISIBLE (-5025 3800);
FORCEADD TAP..1
R 2
(-7325 4700);
FORCEPROP 3 LASTPIN (-7275 4700) SIG_NAME M_G_CPU0_SB_CA<0>
J 0
(-7265 4710);
DISPLAY 0.659574 (-7265 4710);
PAINT MONO (-7265 4710);
DISPLAY INVISIBLE (-7265 4710);
FORCEPROP 1 LASTPIN (-7275 4700) BN 0
J 2
(-7263 4708);
DISPLAY 0.489362 (-7263 4708);
PAINT GREEN (-7263 4708);
FORCEPROP 2 LAST CDS_LIB mstr_standard
J 0
(-7325 4700);
DISPLAY 0.723404 (-7325 4700);
PAINT MONO (-7325 4700);
DISPLAY INVISIBLE (-7325 4700);
FORCEPROP 1 LAST BODY_TYPE PLUMBING
J 2
(-7325 4750);
DISPLAY 0.872340 (-7325 4750);
PAINT GREEN (-7325 4750);
DISPLAY INVISIBLE (-7325 4750);
FORCEPROP 1 LAST HDL_TAP TRUE
J 2
(-7650 4575);
DISPLAY 0.872340 (-7650 4575);
DISPLAY INVISIBLE (-7650 4575);
FORCEPROP 1 LAST PATH I85
J 2
(-7323 4700);
DISPLAY 0.872340 (-7323 4700);
PAINT GREEN (-7323 4700);
DISPLAY INVISIBLE (-7323 4700);
FORCEADD TAP..1
R 2
(-7325 4750);
FORCEPROP 3 LASTPIN (-7275 4750) SIG_NAME M_G_CPU0_SB_CA<1>
J 0
(-7265 4760);
DISPLAY 0.659574 (-7265 4760);
PAINT MONO (-7265 4760);
DISPLAY INVISIBLE (-7265 4760);
FORCEPROP 1 LASTPIN (-7275 4750) BN 1
J 2
(-7263 4758);
DISPLAY 0.489362 (-7263 4758);
PAINT GREEN (-7263 4758);
FORCEPROP 2 LAST CDS_LIB mstr_standard
J 0
(-7325 4750);
DISPLAY 0.723404 (-7325 4750);
PAINT MONO (-7325 4750);
DISPLAY INVISIBLE (-7325 4750);
FORCEPROP 1 LAST BODY_TYPE PLUMBING
J 2
(-7325 4800);
DISPLAY 0.872340 (-7325 4800);
PAINT GREEN (-7325 4800);
DISPLAY INVISIBLE (-7325 4800);
FORCEPROP 1 LAST HDL_TAP TRUE
J 2
(-7650 4625);
DISPLAY 0.872340 (-7650 4625);
DISPLAY INVISIBLE (-7650 4625);
FORCEPROP 1 LAST PATH I86
J 2
(-7323 4750);
DISPLAY 0.872340 (-7323 4750);
PAINT GREEN (-7323 4750);
DISPLAY INVISIBLE (-7323 4750);
FORCEADD TAP..1
R 2
(-7325 4800);
FORCEPROP 3 LASTPIN (-7275 4800) SIG_NAME M_G_CPU0_SB_CA<2>
J 0
(-7265 4810);
DISPLAY 0.659574 (-7265 4810);
PAINT MONO (-7265 4810);
DISPLAY INVISIBLE (-7265 4810);
FORCEPROP 1 LASTPIN (-7275 4800) BN 2
J 2
(-7263 4808);
DISPLAY 0.489362 (-7263 4808);
PAINT GREEN (-7263 4808);
FORCEPROP 2 LAST CDS_LIB mstr_standard
J 0
(-7325 4800);
DISPLAY 0.723404 (-7325 4800);
PAINT MONO (-7325 4800);
DISPLAY INVISIBLE (-7325 4800);
FORCEPROP 1 LAST BODY_TYPE PLUMBING
J 2
(-7325 4850);
DISPLAY 0.872340 (-7325 4850);
PAINT GREEN (-7325 4850);
DISPLAY INVISIBLE (-7325 4850);
FORCEPROP 1 LAST HDL_TAP TRUE
J 2
(-7650 4675);
DISPLAY 0.872340 (-7650 4675);
DISPLAY INVISIBLE (-7650 4675);
FORCEPROP 1 LAST PATH I87
J 2
(-7323 4800);
DISPLAY 0.872340 (-7323 4800);
PAINT GREEN (-7323 4800);
DISPLAY INVISIBLE (-7323 4800);
FORCEADD TAP..1
R 2
(-7325 4850);
FORCEPROP 3 LASTPIN (-7275 4850) SIG_NAME M_G_CPU0_SB_CA<3>
J 0
(-7265 4860);
DISPLAY 0.659574 (-7265 4860);
PAINT MONO (-7265 4860);
DISPLAY INVISIBLE (-7265 4860);
FORCEPROP 1 LASTPIN (-7275 4850) BN 3
J 2
(-7263 4858);
DISPLAY 0.489362 (-7263 4858);
PAINT GREEN (-7263 4858);
FORCEPROP 2 LAST CDS_LIB mstr_standard
J 0
(-7325 4850);
DISPLAY 0.723404 (-7325 4850);
PAINT MONO (-7325 4850);
DISPLAY INVISIBLE (-7325 4850);
FORCEPROP 1 LAST BODY_TYPE PLUMBING
J 2
(-7325 4900);
DISPLAY 0.872340 (-7325 4900);
PAINT GREEN (-7325 4900);
DISPLAY INVISIBLE (-7325 4900);
FORCEPROP 1 LAST HDL_TAP TRUE
J 2
(-7650 4725);
DISPLAY 0.872340 (-7650 4725);
DISPLAY INVISIBLE (-7650 4725);
FORCEPROP 1 LAST PATH I88
J 2
(-7323 4850);
DISPLAY 0.872340 (-7323 4850);
PAINT GREEN (-7323 4850);
DISPLAY INVISIBLE (-7323 4850);
FORCEADD TAP..1
R 2
(-7325 4900);
FORCEPROP 3 LASTPIN (-7275 4900) SIG_NAME M_G_CPU0_SB_CA<4>
J 0
(-7265 4910);
DISPLAY 0.659574 (-7265 4910);
PAINT MONO (-7265 4910);
DISPLAY INVISIBLE (-7265 4910);
FORCEPROP 1 LASTPIN (-7275 4900) BN 4
J 2
(-7263 4908);
DISPLAY 0.489362 (-7263 4908);
PAINT GREEN (-7263 4908);
FORCEPROP 2 LAST CDS_LIB mstr_standard
J 0
(-7325 4900);
DISPLAY 0.723404 (-7325 4900);
PAINT MONO (-7325 4900);
DISPLAY INVISIBLE (-7325 4900);
FORCEPROP 1 LAST BODY_TYPE PLUMBING
J 2
(-7325 4950);
DISPLAY 0.872340 (-7325 4950);
PAINT GREEN (-7325 4950);
DISPLAY INVISIBLE (-7325 4950);
FORCEPROP 1 LAST HDL_TAP TRUE
J 2
(-7650 4775);
DISPLAY 0.872340 (-7650 4775);
DISPLAY INVISIBLE (-7650 4775);
FORCEPROP 1 LAST PATH I89
J 2
(-7323 4900);
DISPLAY 0.872340 (-7323 4900);
PAINT GREEN (-7323 4900);
DISPLAY INVISIBLE (-7323 4900);
FORCEADD OFFPAGE..1
(-7925 3100);
FORCEPROP 2 LAST $XR0 16 
J 0
(-8176 3100);
DISPLAY 0.638298 (-8176 3100);
PAINT MONO (-8176 3100);
FORCEPROP 2 LAST PATH I9
J 0
(-8175 3150);
DISPLAY 1.021277 (-8175 3150);
DISPLAY INVISIBLE (-8175 3150);
FORCEPROP 1 LAST COMMENT_BODY TRUE
J 0
(-7800 3000);
DISPLAY 0.872340 (-7800 3000);
PAINT GREEN (-7800 3000);
DISPLAY INVISIBLE (-7800 3000);
FORCEPROP 1 LAST OFFPAGE TRUE
J 0
(-7600 2975);
DISPLAY 0.872340 (-7600 2975);
PAINT GREEN (-7600 2975);
DISPLAY INVISIBLE (-7600 2975);
FORCEPROP 2 LAST CDS_LIB mstr_standard
J 0
(-7925 3100);
DISPLAY 0.808511 (-7925 3100);
DISPLAY INVISIBLE (-7925 3100);
FORCEADD TAP..1
R 2
(-7325 4950);
FORCEPROP 3 LASTPIN (-7275 4950) SIG_NAME M_G_CPU0_SB_CA<5>
J 0
(-7265 4960);
DISPLAY 0.659574 (-7265 4960);
PAINT MONO (-7265 4960);
DISPLAY INVISIBLE (-7265 4960);
FORCEPROP 1 LASTPIN (-7275 4950) BN 5
J 2
(-7263 4958);
DISPLAY 0.489362 (-7263 4958);
PAINT GREEN (-7263 4958);
FORCEPROP 2 LAST CDS_LIB mstr_standard
J 0
(-7325 4950);
DISPLAY 0.723404 (-7325 4950);
PAINT MONO (-7325 4950);
DISPLAY INVISIBLE (-7325 4950);
FORCEPROP 1 LAST BODY_TYPE PLUMBING
J 2
(-7325 5000);
DISPLAY 0.872340 (-7325 5000);
PAINT GREEN (-7325 5000);
DISPLAY INVISIBLE (-7325 5000);
FORCEPROP 1 LAST HDL_TAP TRUE
J 2
(-7650 4825);
DISPLAY 0.872340 (-7650 4825);
DISPLAY INVISIBLE (-7650 4825);
FORCEPROP 1 LAST PATH I90
J 2
(-7323 4950);
DISPLAY 0.872340 (-7323 4950);
PAINT GREEN (-7323 4950);
DISPLAY INVISIBLE (-7323 4950);
FORCEADD TAP..1
R 2
(-7325 5000);
FORCEPROP 3 LASTPIN (-7275 5000) SIG_NAME M_G_CPU0_SB_CA<6>
J 0
(-7265 5010);
DISPLAY 0.659574 (-7265 5010);
PAINT MONO (-7265 5010);
DISPLAY INVISIBLE (-7265 5010);
FORCEPROP 1 LASTPIN (-7275 5000) BN 6
J 2
(-7263 5008);
DISPLAY 0.489362 (-7263 5008);
PAINT GREEN (-7263 5008);
FORCEPROP 2 LAST CDS_LIB mstr_standard
J 0
(-7325 5000);
DISPLAY 0.723404 (-7325 5000);
PAINT MONO (-7325 5000);
DISPLAY INVISIBLE (-7325 5000);
FORCEPROP 1 LAST BODY_TYPE PLUMBING
J 2
(-7325 5050);
DISPLAY 0.872340 (-7325 5050);
PAINT GREEN (-7325 5050);
DISPLAY INVISIBLE (-7325 5050);
FORCEPROP 1 LAST HDL_TAP TRUE
J 2
(-7650 4875);
DISPLAY 0.872340 (-7650 4875);
DISPLAY INVISIBLE (-7650 4875);
FORCEPROP 1 LAST PATH I91
J 2
(-7323 5000);
DISPLAY 0.872340 (-7323 5000);
PAINT GREEN (-7323 5000);
DISPLAY INVISIBLE (-7323 5000);
FORCEADD TAP..1
R 2
(-7325 5150);
FORCEPROP 3 LASTPIN (-7275 5150) SIG_NAME M_G_CPU0_SA_CA<1>
J 0
(-7265 5160);
DISPLAY 0.659574 (-7265 5160);
PAINT MONO (-7265 5160);
DISPLAY INVISIBLE (-7265 5160);
FORCEPROP 1 LASTPIN (-7275 5150) BN 1
J 2
(-7263 5158);
DISPLAY 0.489362 (-7263 5158);
PAINT GREEN (-7263 5158);
FORCEPROP 2 LAST CDS_LIB mstr_standard
J 0
(-7325 5150);
DISPLAY 0.723404 (-7325 5150);
PAINT MONO (-7325 5150);
DISPLAY INVISIBLE (-7325 5150);
FORCEPROP 1 LAST BODY_TYPE PLUMBING
J 2
(-7325 5200);
DISPLAY 0.872340 (-7325 5200);
PAINT GREEN (-7325 5200);
DISPLAY INVISIBLE (-7325 5200);
FORCEPROP 1 LAST HDL_TAP TRUE
J 2
(-7650 5025);
DISPLAY 0.872340 (-7650 5025);
DISPLAY INVISIBLE (-7650 5025);
FORCEPROP 1 LAST PATH I92
J 2
(-7323 5150);
DISPLAY 0.872340 (-7323 5150);
PAINT GREEN (-7323 5150);
DISPLAY INVISIBLE (-7323 5150);
FORCEADD TAP..1
R 2
(-7325 5100);
FORCEPROP 3 LASTPIN (-7275 5100) SIG_NAME M_G_CPU0_SA_CA<0>
J 0
(-7265 5110);
DISPLAY 0.659574 (-7265 5110);
PAINT MONO (-7265 5110);
DISPLAY INVISIBLE (-7265 5110);
FORCEPROP 1 LASTPIN (-7275 5100) BN 0
J 2
(-7263 5108);
DISPLAY 0.489362 (-7263 5108);
PAINT GREEN (-7263 5108);
FORCEPROP 2 LAST CDS_LIB mstr_standard
J 0
(-7325 5100);
DISPLAY 0.723404 (-7325 5100);
PAINT MONO (-7325 5100);
DISPLAY INVISIBLE (-7325 5100);
FORCEPROP 1 LAST BODY_TYPE PLUMBING
J 2
(-7325 5150);
DISPLAY 0.872340 (-7325 5150);
PAINT GREEN (-7325 5150);
DISPLAY INVISIBLE (-7325 5150);
FORCEPROP 1 LAST HDL_TAP TRUE
J 2
(-7650 4975);
DISPLAY 0.872340 (-7650 4975);
DISPLAY INVISIBLE (-7650 4975);
FORCEPROP 1 LAST PATH I93
J 2
(-7323 5100);
DISPLAY 0.872340 (-7323 5100);
PAINT GREEN (-7323 5100);
DISPLAY INVISIBLE (-7323 5100);
FORCEADD TAP..1
R 2
(-7325 5200);
FORCEPROP 3 LASTPIN (-7275 5200) SIG_NAME M_G_CPU0_SA_CA<2>
J 0
(-7265 5210);
DISPLAY 0.659574 (-7265 5210);
PAINT MONO (-7265 5210);
DISPLAY INVISIBLE (-7265 5210);
FORCEPROP 1 LASTPIN (-7275 5200) BN 2
J 2
(-7263 5208);
DISPLAY 0.489362 (-7263 5208);
PAINT GREEN (-7263 5208);
FORCEPROP 2 LAST CDS_LIB mstr_standard
J 0
(-7325 5200);
DISPLAY 0.723404 (-7325 5200);
PAINT MONO (-7325 5200);
DISPLAY INVISIBLE (-7325 5200);
FORCEPROP 1 LAST BODY_TYPE PLUMBING
J 2
(-7325 5250);
DISPLAY 0.872340 (-7325 5250);
PAINT GREEN (-7325 5250);
DISPLAY INVISIBLE (-7325 5250);
FORCEPROP 1 LAST HDL_TAP TRUE
J 2
(-7650 5075);
DISPLAY 0.872340 (-7650 5075);
DISPLAY INVISIBLE (-7650 5075);
FORCEPROP 1 LAST PATH I94
J 2
(-7323 5200);
DISPLAY 0.872340 (-7323 5200);
PAINT GREEN (-7323 5200);
DISPLAY INVISIBLE (-7323 5200);
FORCEADD TAP..1
R 2
(-7325 5250);
FORCEPROP 3 LASTPIN (-7275 5250) SIG_NAME M_G_CPU0_SA_CA<3>
J 0
(-7265 5260);
DISPLAY 0.659574 (-7265 5260);
PAINT MONO (-7265 5260);
DISPLAY INVISIBLE (-7265 5260);
FORCEPROP 1 LASTPIN (-7275 5250) BN 3
J 2
(-7263 5258);
DISPLAY 0.489362 (-7263 5258);
PAINT GREEN (-7263 5258);
FORCEPROP 2 LAST CDS_LIB mstr_standard
J 0
(-7325 5250);
DISPLAY 0.723404 (-7325 5250);
PAINT MONO (-7325 5250);
DISPLAY INVISIBLE (-7325 5250);
FORCEPROP 1 LAST BODY_TYPE PLUMBING
J 2
(-7325 5300);
DISPLAY 0.872340 (-7325 5300);
PAINT GREEN (-7325 5300);
DISPLAY INVISIBLE (-7325 5300);
FORCEPROP 1 LAST HDL_TAP TRUE
J 2
(-7650 5125);
DISPLAY 0.872340 (-7650 5125);
DISPLAY INVISIBLE (-7650 5125);
FORCEPROP 1 LAST PATH I95
J 2
(-7323 5250);
DISPLAY 0.872340 (-7323 5250);
PAINT GREEN (-7323 5250);
DISPLAY INVISIBLE (-7323 5250);
FORCEADD TAP..1
R 2
(-7325 5300);
FORCEPROP 3 LASTPIN (-7275 5300) SIG_NAME M_G_CPU0_SA_CA<4>
J 0
(-7265 5310);
DISPLAY 0.659574 (-7265 5310);
PAINT MONO (-7265 5310);
DISPLAY INVISIBLE (-7265 5310);
FORCEPROP 1 LASTPIN (-7275 5300) BN 4
J 2
(-7263 5308);
DISPLAY 0.489362 (-7263 5308);
PAINT GREEN (-7263 5308);
FORCEPROP 2 LAST CDS_LIB mstr_standard
J 0
(-7325 5300);
DISPLAY 0.723404 (-7325 5300);
PAINT MONO (-7325 5300);
DISPLAY INVISIBLE (-7325 5300);
FORCEPROP 1 LAST BODY_TYPE PLUMBING
J 2
(-7325 5350);
DISPLAY 0.872340 (-7325 5350);
PAINT GREEN (-7325 5350);
DISPLAY INVISIBLE (-7325 5350);
FORCEPROP 1 LAST HDL_TAP TRUE
J 2
(-7650 5175);
DISPLAY 0.872340 (-7650 5175);
DISPLAY INVISIBLE (-7650 5175);
FORCEPROP 1 LAST PATH I96
J 2
(-7323 5300);
DISPLAY 0.872340 (-7323 5300);
PAINT GREEN (-7323 5300);
DISPLAY INVISIBLE (-7323 5300);
FORCEADD TAP..1
R 2
(-7325 5350);
FORCEPROP 3 LASTPIN (-7275 5350) SIG_NAME M_G_CPU0_SA_CA<5>
J 0
(-7265 5360);
DISPLAY 0.659574 (-7265 5360);
PAINT MONO (-7265 5360);
DISPLAY INVISIBLE (-7265 5360);
FORCEPROP 1 LASTPIN (-7275 5350) BN 5
J 2
(-7263 5358);
DISPLAY 0.489362 (-7263 5358);
PAINT GREEN (-7263 5358);
FORCEPROP 2 LAST CDS_LIB mstr_standard
J 0
(-7325 5350);
DISPLAY 0.723404 (-7325 5350);
PAINT MONO (-7325 5350);
DISPLAY INVISIBLE (-7325 5350);
FORCEPROP 1 LAST BODY_TYPE PLUMBING
J 2
(-7325 5400);
DISPLAY 0.872340 (-7325 5400);
PAINT GREEN (-7325 5400);
DISPLAY INVISIBLE (-7325 5400);
FORCEPROP 1 LAST HDL_TAP TRUE
J 2
(-7650 5225);
DISPLAY 0.872340 (-7650 5225);
DISPLAY INVISIBLE (-7650 5225);
FORCEPROP 1 LAST PATH I97
J 2
(-7323 5350);
DISPLAY 0.872340 (-7323 5350);
PAINT GREEN (-7323 5350);
DISPLAY INVISIBLE (-7323 5350);
FORCEADD TAP..1
R 2
(-7325 5400);
FORCEPROP 3 LASTPIN (-7275 5400) SIG_NAME M_G_CPU0_SA_CA<6>
J 0
(-7265 5410);
DISPLAY 0.659574 (-7265 5410);
PAINT MONO (-7265 5410);
DISPLAY INVISIBLE (-7265 5410);
FORCEPROP 1 LASTPIN (-7275 5400) BN 6
J 2
(-7263 5408);
DISPLAY 0.489362 (-7263 5408);
PAINT GREEN (-7263 5408);
FORCEPROP 2 LAST CDS_LIB mstr_standard
J 0
(-7325 5400);
DISPLAY 0.723404 (-7325 5400);
PAINT MONO (-7325 5400);
DISPLAY INVISIBLE (-7325 5400);
FORCEPROP 1 LAST BODY_TYPE PLUMBING
J 2
(-7325 5450);
DISPLAY 0.872340 (-7325 5450);
PAINT GREEN (-7325 5450);
DISPLAY INVISIBLE (-7325 5450);
FORCEPROP 1 LAST HDL_TAP TRUE
J 2
(-7650 5275);
DISPLAY 0.872340 (-7650 5275);
DISPLAY INVISIBLE (-7650 5275);
FORCEPROP 1 LAST PATH I98
J 2
(-7323 5400);
DISPLAY 0.872340 (-7323 5400);
PAINT GREEN (-7323 5400);
DISPLAY INVISIBLE (-7323 5400);
FORCEADD TAP..1
(-5625 4150);
FORCEPROP 3 LASTPIN (-5675 4150) SIG_NAME M_G_CPU0_SA_DQ<6>
J 0
(-5665 4160);
DISPLAY 0.659574 (-5665 4160);
PAINT MONO (-5665 4160);
DISPLAY INVISIBLE (-5665 4160);
FORCEPROP 1 LASTPIN (-5675 4150) BN 6
J 0
(-5687 4158);
DISPLAY 0.489362 (-5687 4158);
PAINT GREEN (-5687 4158);
FORCEPROP 2 LAST CDS_LIB mstr_standard
J 0
(-5625 4150);
DISPLAY 0.723404 (-5625 4150);
PAINT MONO (-5625 4150);
DISPLAY INVISIBLE (-5625 4150);
FORCEPROP 1 LAST BODY_TYPE PLUMBING
J 0
(-5625 4200);
DISPLAY 0.872340 (-5625 4200);
PAINT GREEN (-5625 4200);
DISPLAY INVISIBLE (-5625 4200);
FORCEPROP 1 LAST HDL_TAP TRUE
J 0
(-5300 4025);
DISPLAY 0.872340 (-5300 4025);
DISPLAY INVISIBLE (-5300 4025);
FORCEPROP 1 LAST PATH I99
J 0
(-5627 4150);
DISPLAY 0.872340 (-5627 4150);
PAINT GREEN (-5627 4150);
DISPLAY INVISIBLE (-5627 4150);
FORCEADD DNS..2
(-8200 2300);
PAINT RED (-8200 2300);
FORCEPROP 2 LAST CDS_LIB mstr_misc
J 0
(-8200 2300);
DISPLAY INVISIBLE (-8200 2300);
FORCEPROP 1 LAST COMMENT_BODY TRUE
R 1
J 0
(-8125 2075);
DISPLAY 0.872340 (-8125 2075);
PAINT PEACH (-8125 2075);
DISPLAY INVISIBLE (-8125 2075);
FORCEADD QUANTA_TITLE_BLOCK_C..1
(0 0);
FORCEPROP 0 LAST CDS_CON_LAST_MODIFIED Fri Mar 11 14:52:56 2022
J 0
(-1885 15);
DISPLAY INVISIBLE (-1885 15);
FORCEPROP 1 LAST CUSTOM_TXT_CDS <CON_LAST_MODIFIED>
J 0
(-1885 15);
DISPLAY 0.978723 (-1885 15);
FORCEPROP 2 LAST CUSTOM_TXT_CDS <XR_PAGE_TITLE>
J 0
(-7890 5250);
DISPLAY 0.638298 (-7890 5250);
PAINT PINK (-7890 5250);
DISPLAY INVISIBLE (-7890 5250);
FORCEPROP 1 LAST CUSTOM_TXT_CDS <NAME_2>
J 0
(-3175 50);
FORCEPROP 1 LAST CUSTOM_TXT_CDS <NAME_1>
J 0
(-3175 175);
FORCEPROP 1 LAST CUSTOM_TXT_CDS <Q_NUMBER>
J 0
(-1403 103);
DISPLAY 1.212766 (-1403 103);
FORCEPROP 1 LAST CUSTOM_TXT_CDS <Q_PROJ>
J 0
(-2382 102);
DISPLAY 1.212766 (-2382 102);
FORCEPROP 1 LAST CUSTOM_TXT_CDS <Q_REV>
J 0
(-184 103);
DISPLAY 1.212766 (-184 103);
FORCEPROP 1 LAST CUSTOM_TXT_CDS <CON_PAGE_NUM> OF <CON_TOTAL_PAGES>
J 0
(-446 18);
DISPLAY 0.978723 (-446 18);
FORCEPROP 1 LAST Q_TITLE DDR5 - CPU0 CHG
J 0
(-9300 50);
DISPLAY 2.446809 (-9300 50);
PAINT GREEN (-9300 50);
FORCEPROP 1 LAST Q_DEPT BU9
J 1
(-3763 49);
DISPLAY 1.957447 (-3763 49);
PAINT GREEN (-3763 49);
FORCEPROP 2 LAST PAGE_BORDER TRUE
J 0
(-7890 5250);
DISPLAY 0.638298 (-7890 5250);
PAINT PINK (-7890 5250);
DISPLAY INVISIBLE (-7890 5250);
FORCEPROP 2 LAST CDS_LIB pure_quanta
J 0
(0 0);
DISPLAY INVISIBLE (0 0);
FORCEPROP 1 LAST CDS_LMAN_SYM_OUTLINE -9475,6775,100,-125
J 0
(0 0);
DISPLAY 0.468085 (0 0);
PAINT GREEN (0 0);
DISPLAY INVISIBLE (0 0);
FORCEPROP 1 LAST COMMENT_BODY TRUE
J 0
(12 -13);
DISPLAY 0.978723 (12 -13);
PAINT GREEN (12 -13);
DISPLAY INVISIBLE (12 -13);
FORCEPROP 2 LAST CDS_XR_PAGE_TITLE CR-91 : @T6G_MB_LIB.T6G(SCH_1):PAGE91
J 0
(-7890 5250);
DISPLAY 0.638298 (-7890 5250);
PAINT PINK (-7890 5250);
DISPLAY INVISIBLE (-7890 5250);
WIRE 17 -1 (-7375 4025)(-7375 4050);
WIRE 17 -1 (-7375 4025)(-7375 3975);
WIRE 17 -1 (-7375 4050)(-7875 4050);
FORCEPROP 2 LAST SIG_NAME M_G_CPU0_SA_CB<7:0>
J 0
(-7875 4060);
DISPLAY 0.489362 (-7875 4060);
WIRE 17 -1 (-7375 3825)(-7375 3875);
WIRE 17 -1 (-7375 3775)(-7375 3825);
WIRE 17 -1 (-7375 3925)(-7375 3875);
WIRE 17 -1 (-7375 3925)(-7375 3975);
WIRE 17 -1 (-7375 3725)(-7375 3775);
WIRE 17 -1 (-7375 3675)(-7375 3725);
WIRE 17 -1 (-7375 3575)(-7375 3525);
WIRE 17 -1 (-7375 3575)(-7375 3600);
WIRE 17 -1 (-7375 3475)(-7375 3525);
WIRE 17 -1 (-7375 3475)(-7375 3425);
WIRE 17 -1 (-7375 3600)(-7875 3600);
FORCEPROP 2 LAST SIG_NAME M_G_CPU0_SB_CB<7:0>
J 0
(-7875 3610);
DISPLAY 0.489362 (-7875 3610);
WIRE 17 -1 (-7375 4725)(-7375 4775);
WIRE 17 -1 (-7375 4775)(-7375 4825);
WIRE 17 -1 (-7375 4825)(-7375 4875);
WIRE 17 -1 (-7375 4875)(-7375 4925);
WIRE 17 -1 (-7375 4925)(-7375 4975);
WIRE 17 -1 (-7375 4975)(-7375 5025);
WIRE 17 -1 (-7375 5025)(-7375 5050);
WIRE 17 -1 (-7375 5050)(-7875 5050);
FORCEPROP 2 LAST SIG_NAME M_G_CPU0_SB_CA<6:0>
J 0
(-7875 5060);
DISPLAY 0.489362 (-7875 5060);
WIRE 17 -1 (-7375 5175)(-7375 5225);
WIRE 17 -1 (-7375 5125)(-7375 5175);
WIRE 17 -1 (-7375 5225)(-7375 5275);
WIRE 17 -1 (-7375 5275)(-7375 5325);
WIRE 17 -1 (-7375 5325)(-7375 5375);
WIRE 17 -1 (-7375 5375)(-7375 5425);
WIRE 17 -1 (-7375 5425)(-7375 5450);
WIRE 17 -1 (-7375 5450)(-7875 5450);
FORCEPROP 2 LAST SIG_NAME M_G_CPU0_SA_CA<6:0>
J 0
(-7875 5460);
DISPLAY 0.489362 (-7875 5460);
WIRE 17 -1 (-7375 3375)(-7375 3425);
WIRE 17 -1 (-7375 3325)(-7375 3375);
WIRE 17 -1 (-7375 3275)(-7375 3325);
WIRE 17 -1 (-7375 3225)(-7375 3275);
WIRE 17 -1 (-5575 5325)(-5575 5275);
WIRE 17 -1 (-5575 5375)(-5575 5325);
WIRE 17 -1 (-5575 5275)(-5575 5225);
WIRE 17 -1 (-5575 5225)(-5575 5175);
WIRE 17 -1 (-5575 5425)(-5575 5375);
WIRE 17 -1 (-5575 5450)(-5575 5425);
WIRE 17 -1 (-5575 5175)(-5575 5125);
WIRE 17 -1 (-5575 5125)(-5575 5075);
WIRE 17 -1 (-5575 5450)(-5075 5450);
FORCEPROP 2 LAST SIG_NAME M_G_CPU0_SA_DQ<31:0>
J 2
(-5075 5460);
DISPLAY 0.489362 (-5075 5460);
WIRE 17 -1 (-5575 5075)(-5575 5025);
WIRE 17 -1 (-5575 5025)(-5575 4975);
WIRE 17 -1 (-5575 4975)(-5575 4925);
WIRE 17 -1 (-5575 4925)(-5575 4875);
WIRE 17 -1 (-5575 4875)(-5575 4825);
WIRE 17 -1 (-5575 4525)(-5575 4575);
WIRE 17 -1 (-5575 4475)(-5575 4525);
WIRE 17 -1 (-5575 4575)(-5575 4625);
WIRE 17 -1 (-5575 4625)(-5575 4675);
WIRE 17 -1 (-5575 4475)(-5575 4425);
WIRE 17 -1 (-5575 4425)(-5575 4375);
WIRE 17 -1 (-5575 4725)(-5575 4675);
WIRE 17 -1 (-5575 4775)(-5575 4725);
WIRE 17 -1 (-5575 4375)(-5575 4325);
WIRE 17 -1 (-5575 4325)(-5575 4275);
WIRE 17 -1 (-5575 4825)(-5575 4775);
WIRE 17 -1 (-5575 4275)(-5575 4225);
WIRE 17 -1 (-5575 4225)(-5575 4175);
WIRE 17 -1 (-5575 4175)(-5575 4125);
WIRE 17 -1 (-5575 4125)(-5575 4075);
WIRE 17 -1 (-5575 4025)(-5575 4075);
WIRE 17 -1 (-5575 3975)(-5575 4025);
WIRE 17 -1 (-5575 3925)(-5575 3975);
WIRE 17 -1 (-5575 3875)(-5575 3925);
WIRE 17 -1 (-5575 3800)(-5575 3775);
WIRE 17 -1 (-5575 3800)(-5075 3800);
FORCEPROP 2 LAST SIG_NAME M_G_CPU0_SB_DQ<31:0>
J 2
(-5075 3810);
DISPLAY 0.489362 (-5075 3810);
WIRE 17 -1 (-5575 3725)(-5575 3675);
WIRE 17 -1 (-5575 3775)(-5575 3725);
WIRE 17 -1 (-5575 3675)(-5575 3625);
WIRE 17 -1 (-5575 3625)(-5575 3575);
WIRE 17 -1 (-5575 3575)(-5575 3525);
WIRE 17 -1 (-5575 3525)(-5575 3475);
WIRE 17 -1 (-5575 3475)(-5575 3425);
WIRE 17 -1 (-5575 3425)(-5575 3375);
WIRE 17 -1 (-5575 3375)(-5575 3325);
WIRE 17 -1 (-5575 3325)(-5575 3275);
WIRE 17 -1 (-5575 3275)(-5575 3225);
WIRE 17 -1 (-5575 3225)(-5575 3175);
WIRE 17 -1 (-5575 3175)(-5575 3125);
WIRE 17 -1 (-5575 3125)(-5575 3075);
WIRE 17 -1 (-5575 3075)(-5575 3025);
WIRE 17 -1 (-5575 2975)(-5575 3025);
WIRE 17 -1 (-5575 2925)(-5575 2975);
WIRE 17 -1 (-5575 2875)(-5575 2925);
WIRE 17 -1 (-5575 2825)(-5575 2875);
WIRE 17 -1 (-5575 2825)(-5575 2775);
WIRE 17 -1 (-5575 2775)(-5575 2725);
WIRE 17 -1 (-5575 2725)(-5575 2675);
WIRE 17 -1 (-5575 2675)(-5575 2625);
WIRE 17 -1 (-5575 2625)(-5575 2575);
WIRE 17 -1 (-5575 2575)(-5575 2525);
WIRE 17 -1 (-5575 2525)(-5575 2475);
WIRE 17 -1 (-5575 2475)(-5575 2425);
WIRE 17 -1 (-5575 2375)(-5575 2425);
WIRE 17 -1 (-5575 2325)(-5575 2375);
WIRE 17 -1 (-5575 2275)(-5575 2325);
WIRE 17 -1 (-5575 2225)(-5575 2275);
WIRE 17 -1 (-2850 4350)(-2850 4250);
WIRE 17 -1 (-2850 4450)(-2850 4350);
WIRE 17 -1 (-2850 4250)(-2850 4150);
WIRE 17 -1 (-2850 4050)(-2850 4150);
WIRE 17 -1 (-2850 4550)(-2850 4450);
WIRE 17 -1 (-2850 4575)(-2850 4550);
WIRE 17 -1 (-2850 3950)(-2850 4050);
WIRE 17 -1 (-2850 3850)(-2850 3950);
WIRE 17 -1 (-2850 4575)(-2350 4575);
FORCEPROP 2 LAST SIG_NAME M_G_CPU0_SA_DQS_DN<9:0>
J 0
(-2885 4585);
DISPLAY 0.489362 (-2885 4585);
WIRE 17 -1 (-3050 4300)(-3050 4200);
WIRE 17 -1 (-3050 4400)(-3050 4300);
WIRE 17 -1 (-3050 4100)(-3050 4200);
WIRE 17 -1 (-3050 4000)(-3050 4100);
WIRE 17 -1 (-3050 4500)(-3050 4400);
WIRE 17 -1 (-3050 4600)(-3050 4500);
WIRE 17 -1 (-3050 3900)(-3050 4000);
WIRE 17 -1 (-3050 3900)(-3050 3800);
WIRE 17 -1 (-3050 4625)(-3050 4600);
WIRE 17 -1 (-3050 4625)(-2350 4625);
FORCEPROP 2 LAST SIG_NAME M_G_CPU0_SA_DQS_DP<9:0>
J 0
(-2885 4635);
DISPLAY 0.489362 (-2885 4635);
WIRE 17 -1 (-3050 3450)(-3050 3350);
WIRE 17 -1 (-3050 3550)(-3050 3450);
WIRE 17 -1 (-3050 3350)(-3050 3250);
WIRE 17 -1 (-3050 3250)(-3050 3150);
WIRE 17 -1 (-3050 3575)(-3050 3550);
WIRE 17 -1 (-3050 3575)(-2350 3575);
FORCEPROP 2 LAST SIG_NAME M_G_CPU0_SB_DQS_DP<9:0>
J 2
(-2350 3585);
DISPLAY 0.489362 (-2350 3585);
WIRE 17 -1 (-2850 3400)(-2850 3300);
WIRE 17 -1 (-2850 3500)(-2850 3400);
WIRE 17 -1 (-2850 3300)(-2850 3200);
WIRE 17 -1 (-2850 3200)(-2850 3100);
WIRE 17 -1 (-2850 3525)(-2850 3500);
WIRE 17 -1 (-2850 3525)(-2350 3525);
FORCEPROP 2 LAST SIG_NAME M_G_CPU0_SB_DQS_DN<9:0>
J 2
(-2350 3535);
DISPLAY 0.489362 (-2350 3535);
WIRE 17 -1 (-3050 3050)(-3050 3150);
WIRE 17 -1 (-3050 2950)(-3050 3050);
WIRE 17 -1 (-3050 2850)(-3050 2950);
WIRE 17 -1 (-2850 3750)(-2850 3650);
WIRE 17 -1 (-2850 3850)(-2850 3750);
WIRE 17 -1 (-3050 3800)(-3050 3700);
WIRE 17 -1 (-2850 2700)(-2850 2600);
WIRE 17 -1 (-2850 2800)(-2850 2700);
WIRE 17 -1 (-2850 2800)(-2850 2900);
WIRE 17 -1 (-2850 2900)(-2850 3000);
WIRE 17 -1 (-2850 3000)(-2850 3100);
WIRE 17 -1 (-3050 2750)(-3050 2650);
WIRE 17 -1 (-3050 2850)(-3050 2750);
WIRE 16 -1 (-6025 1025)(-6025 1100);
WIRE 16 -1 (-8500 3050)(-8500 3125);
WIRE 16 -1 (-8225 2400)(-8225 2425);
WIRE 16 -1 (-8475 2400)(-8475 2425);
WIRE 16 -1 (-8400 2950)(-7075 2950);
WIRE 16 -1 (-8400 3350)(-8400 2950);
WIRE 16 -1 (-8400 3400)(-8400 3350);
WIRE 16 -1 (-8500 3350)(-8400 3350);
WIRE 16 -1 (-8500 3325)(-8500 3350);
WIRE 16 -1 (-7075 2900)(-7875 2900);
FORCEPROP 2 LAST SIG_NAME PD_CHG_CPU0_DIMM0_SAA
J 0
(-7875 2910);
DISPLAY 0.489362 (-7875 2910);
WIRE 16 -1 (-7075 2850)(-7875 2850);
FORCEPROP 2 LAST SIG_NAME I3C_SPD_DDRGL_CPU0_SDA
J 0
(-7885 2860);
DISPLAY 0.489362 (-7885 2860);
WIRE 16 -1 (-7075 2800)(-7175 2800);
FORCEPROP 2 LAST SIG_NAME I3C_SPD_DDRG_CPU0_SCL
J 0
(-7560 2810);
DISPLAY 0.446809 (-7560 2810);
FORCEPROP 2 LASTPROP $XRERR UNIQUE?
J 0
(-7800 2810);
DISPLAY 0.638298 (-7800 2810);
PAINT MONO (-7800 2810);
DISPLAY INVISIBLE (-7800 2810);
WIRE 16 -1 (-7175 2800)(-7175 2700);
WIRE 16 -1 (-7175 2700)(-7275 2700);
WIRE 16 -1 (-7475 2700)(-7875 2700);
FORCEPROP 2 LAST SIG_NAME I3C_SPD_DDRGL_CPU0_SCL
J 0
(-7935 2710);
DISPLAY 0.489362 (-7935 2710);
WIRE 16 -1 (-7075 3050)(-7875 3050);
FORCEPROP 2 LAST SIG_NAME M_G_CPU0_ALERT_N
J 0
(-7860 3060);
DISPLAY 0.489362 (-7860 3060);
WIRE 16 -1 (-7875 2150)(-8225 2150);
WIRE 16 -1 (-7875 2150)(-7875 2550);
WIRE 16 -1 (-8225 2200)(-8225 2150);
WIRE 16 -1 (-8225 2150)(-8250 2150);
WIRE 16 -1 (-7075 2550)(-7875 2550);
FORCEPROP 2 LAST SIG_NAME PWRGD_CHG_CPU0_DIMM0
J 0
(-7735 2560);
DISPLAY 0.489362 (-7735 2560);
FORCEPROP 2 LASTPROP $XRERR UNIQUE?
J 0
(-7975 2560);
DISPLAY 0.638298 (-7975 2560);
PAINT MONO (-7975 2560);
DISPLAY INVISIBLE (-7975 2560);
WIRE 16 -1 (-7075 3100)(-7875 3100);
FORCEPROP 2 LAST SIG_NAME M_G_CPU0_RESET_N
J 0
(-7860 3110);
DISPLAY 0.489362 (-7860 3110);
WIRE 16 -1 (-7075 5100)(-7275 5100);
WIRE 16 -1 (-7075 5000)(-7275 5000);
WIRE 16 -1 (-7075 4950)(-7275 4950);
WIRE 16 -1 (-7075 4900)(-7275 4900);
WIRE 16 -1 (-7075 4850)(-7275 4850);
WIRE 16 -1 (-375 5300)(-375 5250);
WIRE 16 -1 (-375 5300)(-575 5300);
WIRE 16 -1 (-375 5250)(-375 5200);
WIRE 16 -1 (-375 5250)(-575 5250);
WIRE 16 -1 (-375 5200)(-375 5150);
WIRE 16 -1 (-375 5200)(-575 5200);
WIRE 16 -1 (-375 5150)(-575 5150);
WIRE 16 -1 (-375 5150)(-375 5100);
WIRE 16 -1 (-375 5100)(-375 5050);
WIRE 16 -1 (-375 5100)(-575 5100);
WIRE 16 -1 (-375 5050)(-375 5000);
WIRE 16 -1 (-375 5050)(-575 5050);
WIRE 16 -1 (-375 5000)(-375 4950);
WIRE 16 -1 (-375 5000)(-575 5000);
WIRE 16 -1 (-375 4950)(-375 4900);
WIRE 16 -1 (-375 4950)(-575 4950);
WIRE 16 -1 (-375 4900)(-375 4850);
WIRE 16 -1 (-375 4900)(-575 4900);
WIRE 16 -1 (-375 4850)(-375 4800);
WIRE 16 -1 (-375 4850)(-575 4850);
WIRE 16 -1 (-375 4800)(-375 4750);
WIRE 16 -1 (-375 4800)(-575 4800);
WIRE 16 -1 (-375 4750)(-375 4700);
WIRE 16 -1 (-375 4750)(-575 4750);
WIRE 16 -1 (-375 4700)(-375 4650);
WIRE 16 -1 (-375 4700)(-575 4700);
WIRE 16 -1 (-375 4650)(-375 4600);
WIRE 16 -1 (-375 4650)(-575 4650);
WIRE 16 -1 (-375 4600)(-375 4550);
WIRE 16 -1 (-375 4600)(-575 4600);
WIRE 16 -1 (-375 4550)(-375 4500);
WIRE 16 -1 (-375 4550)(-575 4550);
WIRE 16 -1 (-375 4500)(-375 4450);
WIRE 16 -1 (-375 4500)(-575 4500);
WIRE 16 -1 (-375 4450)(-375 4400);
WIRE 16 -1 (-375 4450)(-575 4450);
WIRE 16 -1 (-375 4400)(-375 4350);
WIRE 16 -1 (-375 4400)(-575 4400);
WIRE 16 -1 (-375 4350)(-375 4300);
WIRE 16 -1 (-375 4350)(-575 4350);
WIRE 16 -1 (-375 4300)(-375 4250);
WIRE 16 -1 (-375 4300)(-575 4300);
WIRE 16 -1 (-375 4250)(-375 4200);
WIRE 16 -1 (-375 4250)(-575 4250);
WIRE 16 -1 (-375 4200)(-375 4150);
WIRE 16 -1 (-375 4200)(-575 4200);
WIRE 16 -1 (-375 4150)(-375 4100);
WIRE 16 -1 (-375 4150)(-575 4150);
WIRE 16 -1 (-375 4100)(-575 4100);
WIRE 16 -1 (-375 4100)(-375 4050);
WIRE 16 -1 (-375 4050)(-375 4000);
WIRE 16 -1 (-375 4050)(-575 4050);
WIRE 16 -1 (-375 4000)(-375 3950);
WIRE 16 -1 (-375 4000)(-575 4000);
WIRE 16 -1 (-375 3950)(-375 3900);
WIRE 16 -1 (-375 3950)(-575 3950);
WIRE 16 -1 (-375 3900)(-375 3850);
WIRE 16 -1 (-375 3900)(-575 3900);
WIRE 16 -1 (-375 3850)(-375 3800);
WIRE 16 -1 (-375 3850)(-575 3850);
WIRE 16 -1 (-375 3800)(-375 3750);
WIRE 16 -1 (-375 3800)(-575 3800);
WIRE 16 -1 (-375 3750)(-375 3700);
WIRE 16 -1 (-375 3750)(-575 3750);
WIRE 16 -1 (-375 3700)(-375 3650);
WIRE 16 -1 (-375 3700)(-575 3700);
WIRE 16 -1 (-375 3650)(-375 3600);
WIRE 16 -1 (-375 3650)(-575 3650);
WIRE 16 -1 (-375 3600)(-375 3550);
WIRE 16 -1 (-375 3600)(-575 3600);
WIRE 16 -1 (-375 3550)(-375 3500);
WIRE 16 -1 (-375 3550)(-575 3550);
WIRE 16 -1 (-375 3500)(-375 3450);
WIRE 16 -1 (-375 3500)(-575 3500);
WIRE 16 -1 (-375 3450)(-375 3400);
WIRE 16 -1 (-375 3450)(-575 3450);
WIRE 16 -1 (-375 3400)(-375 3350);
WIRE 16 -1 (-375 3400)(-575 3400);
WIRE 16 -1 (-375 3350)(-375 3300);
WIRE 16 -1 (-375 3350)(-575 3350);
WIRE 16 -1 (-375 3300)(-375 3250);
WIRE 16 -1 (-375 3300)(-575 3300);
WIRE 16 -1 (-375 3250)(-375 3200);
WIRE 16 -1 (-375 3250)(-575 3250);
WIRE 16 -1 (-375 3200)(-375 3150);
WIRE 16 -1 (-375 3200)(-575 3200);
WIRE 16 -1 (-375 3150)(-375 3100);
WIRE 16 -1 (-375 3150)(-575 3150);
WIRE 16 -1 (-375 3100)(-575 3100);
WIRE 16 -1 (-375 3100)(-375 3050);
WIRE 16 -1 (-375 3050)(-375 3000);
WIRE 16 -1 (-375 3050)(-575 3050);
WIRE 16 -1 (-375 3000)(-375 2950);
WIRE 16 -1 (-375 3000)(-575 3000);
WIRE 16 -1 (-375 2950)(-375 2900);
WIRE 16 -1 (-375 2950)(-575 2950);
WIRE 16 -1 (-375 2900)(-375 2850);
WIRE 16 -1 (-375 2900)(-575 2900);
WIRE 16 -1 (-375 2850)(-375 2800);
WIRE 16 -1 (-375 2850)(-575 2850);
WIRE 16 -1 (-375 2800)(-375 2750);
WIRE 16 -1 (-375 2800)(-575 2800);
WIRE 16 -1 (-375 2750)(-375 2700);
WIRE 16 -1 (-375 2750)(-575 2750);
WIRE 16 -1 (-375 2700)(-375 2650);
WIRE 16 -1 (-375 2700)(-575 2700);
WIRE 16 -1 (-375 2650)(-375 2600);
WIRE 16 -1 (-375 2650)(-575 2650);
WIRE 16 -1 (-375 2600)(-375 2550);
WIRE 16 -1 (-375 2600)(-575 2600);
WIRE 16 -1 (-375 2550)(-375 2500);
WIRE 16 -1 (-375 2550)(-575 2550);
WIRE 16 -1 (-375 2500)(-375 2450);
WIRE 16 -1 (-375 2500)(-575 2500);
WIRE 16 -1 (-375 2450)(-375 2400);
WIRE 16 -1 (-375 2450)(-575 2450);
WIRE 16 -1 (-375 2400)(-375 2350);
WIRE 16 -1 (-375 2400)(-575 2400);
WIRE 16 -1 (-375 2350)(-375 2300);
WIRE 16 -1 (-375 2350)(-575 2350);
WIRE 16 -1 (-375 2300)(-375 2250);
WIRE 16 -1 (-375 2300)(-575 2300);
WIRE 16 -1 (-375 2250)(-375 2200);
WIRE 16 -1 (-375 2250)(-575 2250);
WIRE 16 -1 (-375 2200)(-375 2150);
WIRE 16 -1 (-375 2200)(-575 2200);
WIRE 16 -1 (-375 2150)(-375 2050);
WIRE 16 -1 (-375 2150)(-575 2150);
WIRE 16 -1 (-375 2050)(-375 2000);
WIRE 16 -1 (-375 2050)(-575 2050);
WIRE 16 -1 (-375 2000)(-375 1950);
WIRE 16 -1 (-375 2000)(-575 2000);
WIRE 16 -1 (-375 1950)(-375 1750);
WIRE 16 -1 (-375 1950)(-575 1950);
WIRE 16 -1 (-1775 5200)(-1975 5200);
WIRE 16 -1 (-1975 5200)(-1975 5250);
WIRE 16 -1 (-1775 5250)(-1975 5250);
WIRE 16 -1 (-1975 5250)(-1975 5300);
WIRE 16 -1 (-1975 5300)(-1975 6075);
WIRE 16 -1 (-1775 5300)(-1975 5300);
WIRE 16 -1 (-2100 6075)(-1975 6075);
WIRE 16 -1 (-2100 6075)(-2675 6075);
WIRE 16 -1 (-2100 6075)(-2100 5975);
WIRE 16 -1 (-2675 6075)(-2675 6150);
WIRE 16 -1 (-2675 5975)(-2675 6075);
WIRE 16 -1 (-1775 2050)(-1975 2050);
WIRE 16 -1 (-1975 2100)(-1975 2050);
WIRE 16 -1 (-1975 2050)(-1975 1950);
WIRE 16 -1 (-1775 2100)(-1975 2100);
WIRE 16 -1 (-1975 2150)(-1975 2100);
WIRE 16 -1 (-1775 2150)(-1975 2150);
WIRE 16 -1 (-1975 2200)(-1975 2150);
WIRE 16 -1 (-1775 2200)(-1975 2200);
WIRE 16 -1 (-1975 2250)(-1975 2200);
WIRE 16 -1 (-1775 2250)(-1975 2250);
WIRE 16 -1 (-1975 2300)(-1975 2250);
WIRE 16 -1 (-1775 2300)(-1975 2300);
WIRE 16 -1 (-1975 2350)(-1975 2300);
WIRE 16 -1 (-1775 2350)(-1975 2350);
WIRE 16 -1 (-1975 2400)(-1975 2350);
WIRE 16 -1 (-1775 2400)(-1975 2400);
WIRE 16 -1 (-1975 2450)(-1975 2400);
WIRE 16 -1 (-1775 2450)(-1975 2450);
WIRE 16 -1 (-1975 2500)(-1975 2450);
WIRE 16 -1 (-1775 2500)(-1975 2500);
WIRE 16 -1 (-1975 2550)(-1975 2500);
WIRE 16 -1 (-1975 2600)(-1975 2550);
WIRE 16 -1 (-1775 2550)(-1975 2550);
WIRE 16 -1 (-1775 2600)(-1975 2600);
WIRE 16 -1 (-1975 2650)(-1975 2600);
WIRE 16 -1 (-1775 2650)(-1975 2650);
WIRE 16 -1 (-1975 2700)(-1975 2650);
WIRE 16 -1 (-1775 2700)(-1975 2700);
WIRE 16 -1 (-1975 2750)(-1975 2700);
WIRE 16 -1 (-1775 2750)(-1975 2750);
WIRE 16 -1 (-1975 2800)(-1975 2750);
WIRE 16 -1 (-1775 2800)(-1975 2800);
WIRE 16 -1 (-1975 2850)(-1975 2800);
WIRE 16 -1 (-1775 2850)(-1975 2850);
WIRE 16 -1 (-1975 2900)(-1975 2850);
WIRE 16 -1 (-1775 2900)(-1975 2900);
WIRE 16 -1 (-1975 2950)(-1975 2900);
WIRE 16 -1 (-1775 2950)(-1975 2950);
WIRE 16 -1 (-1975 3000)(-1975 2950);
WIRE 16 -1 (-1775 3000)(-1975 3000);
WIRE 16 -1 (-1975 3050)(-1975 3000);
WIRE 16 -1 (-1975 3100)(-1975 3050);
WIRE 16 -1 (-1775 3050)(-1975 3050);
WIRE 16 -1 (-1775 3100)(-1975 3100);
WIRE 16 -1 (-1975 3150)(-1975 3100);
WIRE 16 -1 (-1775 3150)(-1975 3150);
WIRE 16 -1 (-1975 3200)(-1975 3150);
WIRE 16 -1 (-1775 3200)(-1975 3200);
WIRE 16 -1 (-1975 3250)(-1975 3200);
WIRE 16 -1 (-1775 3250)(-1975 3250);
WIRE 16 -1 (-1975 3300)(-1975 3250);
WIRE 16 -1 (-1775 3300)(-1975 3300);
WIRE 16 -1 (-1975 3350)(-1975 3300);
WIRE 16 -1 (-1775 3350)(-1975 3350);
WIRE 16 -1 (-1975 3400)(-1975 3350);
WIRE 16 -1 (-1775 3400)(-1975 3400);
WIRE 16 -1 (-1975 3450)(-1975 3400);
WIRE 16 -1 (-1775 3450)(-1975 3450);
WIRE 16 -1 (-1975 3500)(-1975 3450);
WIRE 16 -1 (-1775 3500)(-1975 3500);
WIRE 16 -1 (-1975 3550)(-1975 3500);
WIRE 16 -1 (-1975 3600)(-1975 3550);
WIRE 16 -1 (-1775 3550)(-1975 3550);
WIRE 16 -1 (-1775 3600)(-1975 3600);
WIRE 16 -1 (-1975 3650)(-1975 3600);
WIRE 16 -1 (-1775 3650)(-1975 3650);
WIRE 16 -1 (-1975 3700)(-1975 3650);
WIRE 16 -1 (-1775 3700)(-1975 3700);
WIRE 16 -1 (-1975 3750)(-1975 3700);
WIRE 16 -1 (-1775 3750)(-1975 3750);
WIRE 16 -1 (-1975 3800)(-1975 3750);
WIRE 16 -1 (-1775 3800)(-1975 3800);
WIRE 16 -1 (-1975 3850)(-1975 3800);
WIRE 16 -1 (-1775 3850)(-1975 3850);
WIRE 16 -1 (-1975 3900)(-1975 3850);
WIRE 16 -1 (-1775 3900)(-1975 3900);
WIRE 16 -1 (-1975 3950)(-1975 3900);
WIRE 16 -1 (-1775 3950)(-1975 3950);
WIRE 16 -1 (-1975 4000)(-1975 3950);
WIRE 16 -1 (-1775 4000)(-1975 4000);
WIRE 16 -1 (-1975 4050)(-1975 4000);
WIRE 16 -1 (-1975 4100)(-1975 4050);
WIRE 16 -1 (-1775 4050)(-1975 4050);
WIRE 16 -1 (-1775 4100)(-1975 4100);
WIRE 16 -1 (-1975 4150)(-1975 4100);
WIRE 16 -1 (-1775 4150)(-1975 4150);
WIRE 16 -1 (-1975 4200)(-1975 4150);
WIRE 16 -1 (-1775 4200)(-1975 4200);
WIRE 16 -1 (-1975 4250)(-1975 4200);
WIRE 16 -1 (-1775 4250)(-1975 4250);
WIRE 16 -1 (-1975 4300)(-1975 4250);
WIRE 16 -1 (-1775 4300)(-1975 4300);
WIRE 16 -1 (-1975 4350)(-1975 4300);
WIRE 16 -1 (-1775 4350)(-1975 4350);
WIRE 16 -1 (-1975 4400)(-1975 4350);
WIRE 16 -1 (-1775 4400)(-1975 4400);
WIRE 16 -1 (-1975 4450)(-1975 4400);
WIRE 16 -1 (-1775 4450)(-1975 4450);
WIRE 16 -1 (-1975 4500)(-1975 4450);
WIRE 16 -1 (-1775 4500)(-1975 4500);
WIRE 16 -1 (-1975 4550)(-1975 4500);
WIRE 16 -1 (-1775 4550)(-1975 4550);
WIRE 16 -1 (-1975 4600)(-1975 4550);
WIRE 16 -1 (-1975 4650)(-1975 4600);
WIRE 16 -1 (-1775 4600)(-1975 4600);
WIRE 16 -1 (-1775 4650)(-1975 4650);
WIRE 16 -1 (-1975 4700)(-1975 4650);
WIRE 16 -1 (-1775 4700)(-1975 4700);
WIRE 16 -1 (-1975 4750)(-1975 4700);
WIRE 16 -1 (-1775 4750)(-1975 4750);
WIRE 16 -1 (-1975 4800)(-1975 4750);
WIRE 16 -1 (-1775 4800)(-1975 4800);
WIRE 16 -1 (-1975 4850)(-1975 4800);
WIRE 16 -1 (-1775 4850)(-1975 4850);
WIRE 16 -1 (-1975 4900)(-1975 4850);
WIRE 16 -1 (-1775 4900)(-1975 4900);
WIRE 16 -1 (-1975 4950)(-1975 4900);
WIRE 16 -1 (-1775 4950)(-1975 4950);
WIRE 16 -1 (-1975 5000)(-1975 4950);
WIRE 16 -1 (-1775 5000)(-1975 5000);
WIRE 16 -1 (-1975 5050)(-1975 5000);
WIRE 16 -1 (-1775 5050)(-1975 5050);
WIRE 16 -1 (-1975 5100)(-1975 5050);
WIRE 16 -1 (-1975 5150)(-1975 5100);
WIRE 16 -1 (-1775 5100)(-1975 5100);
WIRE 16 -1 (-1775 5150)(-1975 5150);
WIRE 16 -1 (-5675 4450)(-5875 4450);
WIRE 16 -1 (-5675 4500)(-5875 4500);
WIRE 16 -1 (-5875 4600)(-5675 4600);
WIRE 16 -1 (-5675 4650)(-5875 4650);
WIRE 16 -1 (-5675 4700)(-5875 4700);
WIRE 16 -1 (-5675 4750)(-5875 4750);
WIRE 16 -1 (-5875 4400)(-5675 4400);
WIRE 16 -1 (-5675 4350)(-5875 4350);
WIRE 16 -1 (-5675 4300)(-5875 4300);
WIRE 16 -1 (-5675 4250)(-5875 4250);
WIRE 16 -1 (-5875 4200)(-5675 4200);
WIRE 16 -1 (-5675 4900)(-5875 4900);
WIRE 16 -1 (-5675 4850)(-5875 4850);
WIRE 16 -1 (-5875 4800)(-5675 4800);
WIRE 16 -1 (-3350 3525)(-3150 3525);
WIRE 16 -1 (-3350 3475)(-2950 3475);
WIRE 16 -1 (-3350 4575)(-3150 4575);
WIRE 16 -1 (-3350 4525)(-2950 4525);
WIRE 16 -1 (-3150 4475)(-3350 4475);
WIRE 16 -1 (-3350 4425)(-2950 4425);
WIRE 16 -1 (-3350 3275)(-2950 3275);
WIRE 16 -1 (-3150 4375)(-3350 4375);
WIRE 16 -1 (-3150 3225)(-3350 3225);
WIRE 16 -1 (-3350 3175)(-2950 3175);
WIRE 16 -1 (-3350 4225)(-2950 4225);
WIRE 16 -1 (-3350 3125)(-3150 3125);
WIRE 16 -1 (-3350 3075)(-2950 3075);
WIRE 16 -1 (-3350 4175)(-3150 4175);
WIRE 16 -1 (-3350 4125)(-2950 4125);
WIRE 16 -1 (-3150 3025)(-3350 3025);
WIRE 16 -1 (-3350 2975)(-2950 2975);
WIRE 16 -1 (-3150 4075)(-3350 4075);
WIRE 16 -1 (-3350 4025)(-2950 4025);
WIRE 16 -1 (-3150 2925)(-3350 2925);
WIRE 16 -1 (-3350 2875)(-2950 2875);
WIRE 16 -1 (-3150 3975)(-3350 3975);
WIRE 16 -1 (-3350 3925)(-2950 3925);
WIRE 16 -1 (-3150 2825)(-3350 2825);
WIRE 16 -1 (-3350 2775)(-2950 2775);
WIRE 16 -1 (-3150 3875)(-3350 3875);
WIRE 16 -1 (-3350 3825)(-2950 3825);
WIRE 16 -1 (-3350 2725)(-3150 2725);
WIRE 16 -1 (-3350 2675)(-2950 2675);
WIRE 16 -1 (-3350 3775)(-3150 3775);
WIRE 16 -1 (-3350 3725)(-2950 3725);
WIRE 16 -1 (-3150 2625)(-3350 2625);
WIRE 16 -1 (-3350 2575)(-2950 2575);
WIRE 16 -1 (-3150 3675)(-3350 3675);
WIRE 16 -1 (-3350 3625)(-2950 3625);
WIRE 16 -1 (-3150 3325)(-3350 3325);
WIRE 16 -1 (-3350 3375)(-2950 3375);
WIRE 16 -1 (-3150 3425)(-3350 3425);
WIRE 16 -1 (-3150 4275)(-3350 4275);
WIRE 16 -1 (-3350 4325)(-2950 4325);
WIRE 16 -1 (-5675 4950)(-5875 4950);
WIRE 16 -1 (-5875 5000)(-5675 5000);
WIRE 16 -1 (-5675 5050)(-5875 5050);
WIRE 16 -1 (-5675 5100)(-5875 5100);
WIRE 16 -1 (-5675 5350)(-5875 5350);
WIRE 16 -1 (-5875 5400)(-5675 5400);
WIRE 16 -1 (-7075 2150)(-7750 2150);
FORCEPROP 2 LAST SIG_NAME TP_CHG_CPU0_DIMM0_RFU_0
J 0
(-7750 2160);
DISPLAY 0.489362 (-7750 2160);
FORCEPROP 2 LASTPROP $XRERR UNIQUE?
J 0
(-7990 2150);
DISPLAY 0.638298 (-7990 2150);
PAINT MONO (-7990 2150);
DISPLAY INVISIBLE (-7990 2150);
WIRE 16 -1 (-7075 2200)(-7750 2200);
FORCEPROP 2 LAST SIG_NAME TP_CHG_CPU0_DIMM0_RFU_1
J 0
(-7750 2210);
DISPLAY 0.489362 (-7750 2210);
FORCEPROP 2 LASTPROP $XRERR UNIQUE?
J 0
(-7990 2200);
DISPLAY 0.638298 (-7990 2200);
PAINT MONO (-7990 2200);
DISPLAY INVISIBLE (-7990 2200);
WIRE 16 -1 (-7075 2250)(-7750 2250);
FORCEPROP 2 LAST SIG_NAME TP_CHG_CPU0_DIMM0_RFU_2
J 0
(-7750 2260);
DISPLAY 0.489362 (-7750 2260);
FORCEPROP 2 LASTPROP $XRERR UNIQUE?
J 0
(-7990 2250);
DISPLAY 0.638298 (-7990 2250);
PAINT MONO (-7990 2250);
DISPLAY INVISIBLE (-7990 2250);
WIRE 16 -1 (-7075 2300)(-7750 2300);
FORCEPROP 2 LAST SIG_NAME TP_CHG_CPU0_DIMM0_RFU_3
J 0
(-7750 2310);
DISPLAY 0.489362 (-7750 2310);
FORCEPROP 2 LASTPROP $XRERR UNIQUE?
J 0
(-7990 2300);
DISPLAY 0.638298 (-7990 2300);
PAINT MONO (-7990 2300);
DISPLAY INVISIBLE (-7990 2300);
WIRE 16 -1 (-7075 2350)(-7750 2350);
FORCEPROP 2 LAST SIG_NAME TP_CHG_CPU0_DIMM0_RFU_4
J 0
(-7750 2360);
DISPLAY 0.489362 (-7750 2360);
FORCEPROP 2 LASTPROP $XRERR UNIQUE?
J 0
(-7990 2350);
DISPLAY 0.638298 (-7990 2350);
PAINT MONO (-7990 2350);
DISPLAY INVISIBLE (-7990 2350);
WIRE 16 -1 (-7075 2400)(-7750 2400);
FORCEPROP 2 LAST SIG_NAME TP_CHG_CPU0_DIMM0_RFU_5
J 0
(-7750 2410);
DISPLAY 0.489362 (-7750 2410);
FORCEPROP 2 LASTPROP $XRERR UNIQUE?
J 0
(-7990 2400);
DISPLAY 0.638298 (-7990 2400);
PAINT MONO (-7990 2400);
DISPLAY INVISIBLE (-7990 2400);
WIRE 16 -1 (-7075 2450)(-7750 2450);
FORCEPROP 2 LAST SIG_NAME TP_CHG_CPU0_DIMM0_RFU_6
J 0
(-7750 2460);
DISPLAY 0.489362 (-7750 2460);
FORCEPROP 2 LASTPROP $XRERR UNIQUE?
J 0
(-7990 2450);
DISPLAY 0.638298 (-7990 2450);
PAINT MONO (-7990 2450);
DISPLAY INVISIBLE (-7990 2450);
WIRE 16 -1 (-7075 4550)(-7875 4550);
FORCEPROP 2 LAST SIG_NAME M_G_CPU0_SB_PAR
J 0
(-7875 4560);
DISPLAY 0.489362 (-7875 4560);
WIRE 16 -1 (-7075 4600)(-7875 4600);
FORCEPROP 2 LAST SIG_NAME M_G_CPU0_SA_PAR
J 0
(-7875 4610);
DISPLAY 0.489362 (-7875 4610);
WIRE 16 -1 (-7075 1950)(-7875 1950);
FORCEPROP 2 LAST SIG_NAME M_G_CPU0_SB_RSP<0>
J 0
(-7875 1960);
DISPLAY 0.489362 (-7875 1960);
WIRE 16 -1 (-7075 2000)(-7875 2000);
FORCEPROP 2 LAST SIG_NAME M_G_CPU0_SA_RSP<0>
J 0
(-7875 2010);
DISPLAY 0.489362 (-7875 2010);
WIRE 16 -1 (-5675 2200)(-5875 2200);
WIRE 16 -1 (-5675 2250)(-5875 2250);
WIRE 16 -1 (-5675 2300)(-5875 2300);
WIRE 16 -1 (-5875 2350)(-5675 2350);
WIRE 16 -1 (-5675 2400)(-5875 2400);
WIRE 16 -1 (-5675 2450)(-5875 2450);
WIRE 16 -1 (-5675 2500)(-5875 2500);
WIRE 16 -1 (-5875 2550)(-5675 2550);
WIRE 16 -1 (-5675 2600)(-5875 2600);
WIRE 16 -1 (-5675 2650)(-5875 2650);
WIRE 16 -1 (-5675 2700)(-5875 2700);
WIRE 16 -1 (-5875 2750)(-5675 2750);
WIRE 16 -1 (-5675 2800)(-5875 2800);
WIRE 16 -1 (-5675 2850)(-5875 2850);
WIRE 16 -1 (-5675 2900)(-5875 2900);
WIRE 16 -1 (-5875 2950)(-5675 2950);
WIRE 16 -1 (-5675 3000)(-5875 3000);
WIRE 16 -1 (-5675 3050)(-5875 3050);
WIRE 16 -1 (-5675 3100)(-5875 3100);
WIRE 16 -1 (-5875 3150)(-5675 3150);
WIRE 16 -1 (-5675 3200)(-5875 3200);
WIRE 16 -1 (-5675 3250)(-5875 3250);
WIRE 16 -1 (-5675 3300)(-5875 3300);
WIRE 16 -1 (-5875 3350)(-5675 3350);
WIRE 16 -1 (-5675 3400)(-5875 3400);
WIRE 16 -1 (-5675 3450)(-5875 3450);
WIRE 16 -1 (-5675 3500)(-5875 3500);
WIRE 16 -1 (-5875 3550)(-5675 3550);
WIRE 16 -1 (-5675 3600)(-5875 3600);
WIRE 16 -1 (-5675 3650)(-5875 3650);
WIRE 16 -1 (-5675 3700)(-5875 3700);
WIRE 16 -1 (-5875 3750)(-5675 3750);
WIRE 16 -1 (-5675 3850)(-5875 3850);
WIRE 16 -1 (-5675 3900)(-5875 3900);
WIRE 16 -1 (-5675 3950)(-5875 3950);
WIRE 16 -1 (-5875 4000)(-5675 4000);
WIRE 16 -1 (-5675 4050)(-5875 4050);
WIRE 16 -1 (-5675 4100)(-5875 4100);
WIRE 16 -1 (-5675 4150)(-5875 4150);
WIRE 16 -1 (-5675 4550)(-5875 4550);
WIRE 16 -1 (-5675 5150)(-5875 5150);
WIRE 16 -1 (-5875 5200)(-5675 5200);
WIRE 16 -1 (-5675 5250)(-5875 5250);
WIRE 16 -1 (-5675 5300)(-5875 5300);
WIRE 16 -1 (-7075 4300)(-7875 4300);
FORCEPROP 2 LAST SIG_NAME M_G_CPU0_SB_CS_N<1>
J 0
(-7875 4310);
DISPLAY 0.489362 (-7875 4310);
WIRE 16 -1 (-7075 4450)(-7875 4450);
FORCEPROP 2 LAST SIG_NAME M_G_CPU0_SA_CS_N<1>
J 0
(-7875 4460);
DISPLAY 0.489362 (-7875 4460);
WIRE 16 -1 (-7075 4250)(-7875 4250);
FORCEPROP 2 LAST SIG_NAME M_G_CPU0_SB_CS_N<0>
J 0
(-7875 4260);
DISPLAY 0.489362 (-7875 4260);
WIRE 16 -1 (-7075 4400)(-7875 4400);
FORCEPROP 2 LAST SIG_NAME M_G_CPU0_SA_CS_N<0>
J 0
(-7875 4410);
DISPLAY 0.489362 (-7875 4410);
WIRE 16 -1 (-7075 4150)(-7875 4150);
FORCEPROP 2 LAST SIG_NAME M_G_CPU0_CLK_DP<0>
J 0
(-7875 4160);
DISPLAY 0.489362 (-7875 4160);
WIRE 16 -1 (-7075 4100)(-7875 4100);
FORCEPROP 2 LAST SIG_NAME M_G_CPU0_CLK_DN<0>
J 0
(-7875 4110);
DISPLAY 0.489362 (-7875 4110);
WIRE 16 -1 (-7075 3200)(-7275 3200);
WIRE 16 -1 (-7075 3250)(-7275 3250);
WIRE 16 -1 (-7075 3300)(-7275 3300);
WIRE 16 -1 (-7075 3350)(-7275 3350);
WIRE 16 -1 (-7075 3400)(-7275 3400);
WIRE 16 -1 (-7075 3450)(-7275 3450);
WIRE 16 -1 (-7075 3500)(-7275 3500);
WIRE 16 -1 (-7075 3650)(-7275 3650);
WIRE 16 -1 (-7075 3750)(-7275 3750);
WIRE 16 -1 (-7075 3800)(-7275 3800);
WIRE 16 -1 (-7075 3900)(-7275 3900);
WIRE 16 -1 (-7075 3950)(-7275 3950);
WIRE 16 -1 (-7075 5400)(-7275 5400);
WIRE 16 -1 (-7075 5350)(-7275 5350);
WIRE 16 -1 (-7075 5300)(-7275 5300);
WIRE 16 -1 (-7075 5250)(-7275 5250);
WIRE 16 -1 (-7075 4800)(-7275 4800);
WIRE 16 -1 (-7075 5200)(-7275 5200);
WIRE 16 -1 (-7075 4750)(-7275 4750);
WIRE 16 -1 (-7075 5150)(-7275 5150);
WIRE 16 -1 (-7075 4700)(-7275 4700);
WIRE 16 -1 (-7075 3550)(-7275 3550);
WIRE 16 -1 (-7075 3700)(-7275 3700);
WIRE 16 -1 (-7075 3850)(-7275 3850);
WIRE 16 -1 (-7075 4000)(-7275 4000);
WIRE 16 -1 (-8850 2150)(-8475 2150);
FORCEPROP 2 LAST SIG_NAME PWRGD_CHGL_CPU0
J 0
(-8835 2160);
DISPLAY 0.489362 (-8835 2160);
WIRE 16 -1 (-8475 2200)(-8475 2150);
WIRE 16 -1 (-8475 2150)(-8450 2150);
WIRE 16 -1 (-6025 1375)(-6025 1300);
WIRE 16 -1 (-6025 1375)(-6750 1375);
FORCEPROP 2 LAST SIG_NAME PD_CHG_CPU0_DIMM0_SAA
J 0
(-6735 1385);
DISPLAY 0.489362 (-6735 1385);
WIRE 16 -1 (-2100 5650)(-2675 5650);
WIRE 16 -1 (-2100 5650)(-2100 5775);
WIRE 16 -1 (-2675 5650)(-2675 5775);
WIRE 16 -1 (-2675 5650)(-2675 5575);
DOT 1 (-375 5200);
DOT 1 (-375 5150);
DOT 1 (-375 5100);
DOT 1 (-375 5050);
DOT 1 (-375 5000);
DOT 1 (-375 4950);
DOT 1 (-375 4850);
DOT 1 (-375 4900);
DOT 1 (-375 4750);
DOT 1 (-375 4800);
DOT 1 (-375 4700);
DOT 1 (-375 4650);
DOT 1 (-375 4600);
DOT 1 (-375 4450);
DOT 1 (-375 4500);
DOT 1 (-375 4550);
DOT 1 (-375 4400);
DOT 1 (-375 4350);
DOT 1 (-375 4300);
DOT 1 (-375 4250);
DOT 1 (-375 4200);
DOT 1 (-1975 5300);
DOT 1 (-1975 5250);
DOT 1 (-1975 5100);
DOT 1 (-1975 5000);
DOT 1 (-1975 5050);
DOT 1 (-1975 4850);
DOT 1 (-1975 4900);
DOT 1 (-1975 4700);
DOT 1 (-1975 4750);
DOT 1 (-1975 4800);
DOT 1 (-1975 4650);
DOT 1 (-1975 4600);
DOT 1 (-1975 4550);
DOT 1 (-1975 4450);
DOT 1 (-1975 4500);
DOT 1 (-1975 4400);
DOT 1 (-1975 4350);
DOT 1 (-1975 4300);
DOT 1 (-1975 4250);
DOT 1 (-1975 4200);
DOT 1 (-375 4150);
DOT 1 (-375 4100);
DOT 1 (-375 4050);
DOT 1 (-375 4000);
DOT 1 (-375 3950);
DOT 1 (-375 3900);
DOT 1 (-375 3850);
DOT 1 (-375 3800);
DOT 1 (-375 3700);
DOT 1 (-375 3750);
DOT 1 (-375 3600);
DOT 1 (-375 3650);
DOT 1 (-375 3550);
DOT 1 (-375 3450);
DOT 1 (-375 3500);
DOT 1 (-375 3300);
DOT 1 (-375 3350);
DOT 1 (-375 3400);
DOT 1 (-375 3200);
DOT 1 (-375 3250);
DOT 1 (-375 3150);
DOT 1 (-375 3100);
DOT 1 (-375 3050);
DOT 1 (-375 3000);
DOT 1 (-375 2950);
DOT 1 (-375 2900);
DOT 1 (-375 2800);
DOT 1 (-375 2850);
DOT 1 (-375 2750);
DOT 1 (-375 2700);
DOT 1 (-375 2650);
DOT 1 (-375 2600);
DOT 1 (-375 2550);
DOT 1 (-375 2500);
DOT 1 (-375 2450);
DOT 1 (-375 2400);
DOT 1 (-375 2350);
DOT 1 (-375 2300);
DOT 1 (-375 2150);
DOT 1 (-375 2250);
DOT 1 (-375 2200);
DOT 1 (-375 2050);
DOT 1 (-375 1950);
DOT 1 (-375 2000);
DOT 1 (-1975 4100);
DOT 1 (-1975 4150);
DOT 1 (-1975 4050);
DOT 1 (-1975 3950);
DOT 1 (-1975 4000);
DOT 1 (-1975 3900);
DOT 1 (-1975 3850);
DOT 1 (-1975 3800);
DOT 1 (-1975 3750);
DOT 1 (-1975 3700);
DOT 1 (-1975 3550);
DOT 1 (-1975 3650);
DOT 1 (-1975 3600);
DOT 1 (-1975 3450);
DOT 1 (-1975 3500);
DOT 1 (-1975 3400);
DOT 1 (-1975 3350);
DOT 1 (-1975 3300);
DOT 1 (-1975 3250);
DOT 1 (-1975 3200);
DOT 1 (-1975 3150);
DOT 1 (-1975 3050);
DOT 1 (-1975 3100);
DOT 1 (-1975 2950);
DOT 1 (-1975 3000);
DOT 1 (-1975 2900);
DOT 1 (-1975 2800);
DOT 1 (-1975 2850);
DOT 1 (-1975 2650);
DOT 1 (-1975 2700);
DOT 1 (-1975 2750);
DOT 1 (-1975 2550);
DOT 1 (-1975 2600);
DOT 1 (-1975 2500);
DOT 1 (-1975 2400);
DOT 1 (-1975 2450);
DOT 1 (-1975 2300);
DOT 1 (-1975 2350);
DOT 1 (-1975 2150);
DOT 1 (-1975 2250);
DOT 1 (-1975 2200);
DOT 1 (-1975 2050);
DOT 1 (-1975 2100);
DOT 1 (-8400 3350);
DOT 1 (-8225 2150);
DOT 1 (-8475 2150);
DOT 1 (-2675 5650);
DOT 1 (-2100 6075);
DOT 1 (-2675 6075);
DOT 1 (-1975 4950);
DOT 1 (-375 5250);
QUIT
